FILE_TYPE = MACRO_DRAWING;
SET COLOR_WIRE YELLOW;
SET COLOR_PROP ORANGE;
SET COLOR_DOT WHITE;
SET COLOR_ARC YELLOW;
SET COLOR_BODY GREEN;
SET COLOR_NOTE PURPLE;
SET PROP_DISPLAY VALUE;
SET PAGE_NUMBER P375;
FORCEADD UNIVERSAL_GND..1
(-7875 1500);
FORCEPROP 3 LASTPIN (-7875 1550) SIG_NAME GND\g
J 0
(-7865 1560);
DISPLAY 0.659574 (-7865 1560);
PAINT MONO (-7865 1560);
DISPLAY INVISIBLE (-7865 1560);
FORCEPROP 2 LAST CDS_LIB pure_quanta_power
J 0
(-7875 1500);
DISPLAY INVISIBLE (-7875 1500);
FORCEPROP 1 LAST HDL_POWER GND
J 1
(-7850 1425);
DISPLAY 0.872340 (-7850 1425);
PAINT GREEN (-7850 1425);
DISPLAY INVISIBLE (-7850 1425);
FORCEPROP 1 LAST PATH I1
J 0
(-7800 1500);
DISPLAY 0.872340 (-7800 1500);
PAINT AQUA (-7800 1500);
DISPLAY INVISIBLE (-7800 1500);
FORCEADD MOSFET_NCH_DUAL..2
(-7925 4400);
FORCEPROP 1 LAST LOCATION Q84
J 0
(-7774 4376);
DISPLAY 0.723404 (-7774 4376);
PAINT AQUA (-7774 4376);
FORCEPROP 2 LAST SEC 2
J 0
(-7750 4525);
DISPLAY 0.680851 (-7750 4525);
PAINT MONO (-7750 4525);
DISPLAY INVISIBLE (-7750 4525);
FORCEPROP 2 LASTPIN (-7875 4600) $PN 3
R 1
J 0
(-7885 4610);
DISPLAY 0.723404 (-7885 4610);
PAINT MONO (-7885 4610);
FORCEPROP 2 LASTPIN (-8125 4350) $PN 5
J 2
(-8135 4360);
DISPLAY 0.723404 (-8135 4360);
PAINT MONO (-8135 4360);
FORCEPROP 2 LASTPIN (-7875 4200) $PN 4
R 1
J 2
(-7885 4190);
DISPLAY 0.723404 (-7885 4190);
PAINT MONO (-7885 4190);
FORCEPROP 2 LAST VALUE PJT138K
J 0
(-7750 4425);
DISPLAY 0.723404 (-7750 4425);
PAINT SKYBLUE (-7750 4425);
FORCEPROP 2 LAST PART_TYPE SMLF
J 0
(-7750 4475);
DISPLAY 1.021277 (-7750 4475);
FORCEPROP 1 LAST MATERIAL IC
J 0
(-7774 4251);
DISPLAY 0.723404 (-7774 4251);
PAINT SKYBLUE (-7774 4251);
FORCEPROP 1 LAST CDS_LMAN_SYM_OUTLINE -150,150,150,-150
J 0
(-7925 4400);
DISPLAY 0.468085 (-7925 4400);
PAINT GREEN (-7925 4400);
DISPLAY INVISIBLE (-7925 4400);
FORCEPROP 1 LAST NEEDS_NO_SIZE TRUE
J 0
(-7775 4291);
DISPLAY 0.468085 (-7775 4291);
PAINT GREEN (-7775 4291);
DISPLAY INVISIBLE (-7775 4291);
FORCEPROP 2 LAST CDS_LIB pure_quanta
J 0
(-7925 4400);
DISPLAY INVISIBLE (-7925 4400);
FORCEPROP 2 LAST SEC_TYPE 
J 0
(-7750 4525);
DISPLAY 1.021277 (-7750 4525);
DISPLAY INVISIBLE (-7750 4525);
FORCEPROP 1 LAST PATH I10
J 0
(-7775 4250);
DISPLAY 0.723404 (-7775 4250);
PAINT GREEN (-7775 4250);
DISPLAY INVISIBLE (-7775 4250);
FORCEPROP 1 LAST PART_NUMBER BAM138K0003
J 0
(-7774 4306);
DISPLAY 0.723404 (-7774 4306);
PAINT BLUE (-7774 4306);
DISPLAY INVISIBLE (-7774 4306);
FORCEADD MOSFET_NCH_DUAL..1
(-7925 5725);
FORCEPROP 1 LAST LOCATION Q84
J 0
(-7774 5699);
DISPLAY 0.723404 (-7774 5699);
PAINT GREEN (-7774 5699);
FORCEPROP 0 LAST $SEC 1
J 0
(-7750 5850);
DISPLAY INVISIBLE (-7750 5850);
FORCEPROP 0 LAST CDS_SEC 1
J 0
(-7750 5850);
DISPLAY INVISIBLE (-7750 5850);
FORCEPROP 0 LASTPIN (-7875 5925) $PN 6
R 1
J 0
(-7885 5935);
DISPLAY 0.808511 (-7885 5935);
FORCEPROP 0 LASTPIN (-8125 5675) $PN 2
J 2
(-8135 5685);
DISPLAY 0.808511 (-8135 5685);
FORCEPROP 0 LASTPIN (-7875 5525) $PN 1
R 1
J 2
(-7885 5515);
DISPLAY 0.808511 (-7885 5515);
FORCEPROP 1 LAST MATERIAL IC
J 0
(-7774 5574);
DISPLAY 0.723404 (-7774 5574);
PAINT GREEN (-7774 5574);
FORCEPROP 2 LAST PART_TYPE SMLF
J 0
(-7750 5800);
DISPLAY 1.021277 (-7750 5800);
FORCEPROP 2 LAST VALUE PJT138K
J 0
(-7750 5750);
DISPLAY 1.021277 (-7750 5750);
FORCEPROP 1 LAST NEEDS_NO_SIZE TRUE
J 0
(-7925 5724);
DISPLAY 0.468085 (-7925 5724);
PAINT GREEN (-7925 5724);
DISPLAY INVISIBLE (-7925 5724);
FORCEPROP 1 LAST CDS_LMAN_SYM_OUTLINE -150,150,150,-150
J 0
(-7925 5725);
DISPLAY 0.468085 (-7925 5725);
PAINT GREEN (-7925 5725);
DISPLAY INVISIBLE (-7925 5725);
FORCEPROP 2 LAST CDS_LIB pure_quanta
J 0
(-7925 5725);
DISPLAY INVISIBLE (-7925 5725);
FORCEPROP 1 LAST PATH I11
J 0
(-7925 5725);
DISPLAY 0.723404 (-7925 5725);
PAINT GREEN (-7925 5725);
DISPLAY INVISIBLE (-7925 5725);
FORCEPROP 1 LAST PART_NUMBER BAM138K0003
J 0
(-7774 5639);
DISPLAY 0.723404 (-7774 5639);
PAINT GREEN (-7774 5639);
DISPLAY INVISIBLE (-7774 5639);
FORCEADD UNIVERSAL_GND..1
(-7875 5375);
FORCEPROP 3 LASTPIN (-7875 5425) SIG_NAME GND\g
J 0
(-7865 5435);
DISPLAY 0.659574 (-7865 5435);
PAINT MONO (-7865 5435);
DISPLAY INVISIBLE (-7865 5435);
FORCEPROP 2 LAST CDS_LIB pure_quanta_power
J 0
(-7875 5375);
DISPLAY INVISIBLE (-7875 5375);
FORCEPROP 1 LAST HDL_POWER GND
J 1
(-7850 5300);
DISPLAY 0.872340 (-7850 5300);
PAINT GREEN (-7850 5300);
DISPLAY INVISIBLE (-7850 5300);
FORCEPROP 1 LAST PATH I12
J 0
(-7800 5375);
DISPLAY 0.872340 (-7800 5375);
PAINT AQUA (-7800 5375);
DISPLAY INVISIBLE (-7800 5375);
FORCEADD Q_LED..1
R 2
(-6850 2125);
FORCEPROP 1 LAST LOCATION D83
J 0
(-6950 2050);
DISPLAY 0.723404 (-6950 2050);
PAINT GREEN (-6950 2050);
FORCEPROP 0 LAST $SEC 1
J 0
(-6950 2100);
DISPLAY INVISIBLE (-6950 2100);
FORCEPROP 0 LAST CDS_SEC 1
J 0
(-6950 2100);
DISPLAY INVISIBLE (-6950 2100);
FORCEPROP 0 LASTPIN (-6700 2125) $PN A
J 0
(-6690 2135);
DISPLAY 0.808511 (-6690 2135);
FORCEPROP 0 LASTPIN (-7000 2125) $PN C
J 2
(-7010 2135);
DISPLAY 0.808511 (-7010 2135);
FORCEPROP 1 LAST MATERIAL IC
J 0
(-6825 1950);
DISPLAY 0.723404 (-6825 1950);
PAINT GREEN (-6825 1950);
FORCEPROP 0 LAST PACK_TYPE SMLF
J 0
(-6950 1950);
DISPLAY 0.638298 (-6950 1950);
FORCEPROP 2 LAST COLOR LED_BLUE
J 0
(-6950 2000);
DISPLAY 0.638298 (-6950 2000);
FORCEPROP 2 LAST MANUF_PN LTST-C281TBKT-5A
J 0
(-6950 1850);
DISPLAY 0.638298 (-6950 1850);
FORCEPROP 2 LAST CDS_LIB pure_quanta
J 0
(-6850 2125);
DISPLAY INVISIBLE (-6850 2125);
FORCEPROP 1 LAST NEEDS_NO_SIZE TRUE
J 2
(-6828 2147);
DISPLAY 0.468085 (-6828 2147);
PAINT GREEN (-6828 2147);
DISPLAY INVISIBLE (-6828 2147);
FORCEPROP 1 LAST PATH I13
J 2
(-6975 2205);
DISPLAY 0.723404 (-6975 2205);
PAINT GREEN (-6975 2205);
DISPLAY INVISIBLE (-6975 2205);
FORCEPROP 1 LAST PART_NUMBER BEBL0172Z00
J 0
(-6950 1900);
DISPLAY 0.574468 (-6950 1900);
PAINT GREEN (-6950 1900);
DISPLAY INVISIBLE (-6950 1900);
FORCEADD Q_LED..1
R 2
(-6850 3450);
FORCEPROP 1 LAST LOCATION D82
J 0
(-6950 3375);
DISPLAY 0.723404 (-6950 3375);
PAINT GREEN (-6950 3375);
FORCEPROP 0 LAST $SEC 1
J 0
(-6950 3425);
DISPLAY INVISIBLE (-6950 3425);
FORCEPROP 0 LAST CDS_SEC 1
J 0
(-6950 3425);
DISPLAY INVISIBLE (-6950 3425);
FORCEPROP 0 LASTPIN (-6700 3450) $PN A
J 0
(-6690 3460);
DISPLAY 0.808511 (-6690 3460);
FORCEPROP 0 LASTPIN (-7000 3450) $PN C
J 2
(-7010 3460);
DISPLAY 0.808511 (-7010 3460);
FORCEPROP 2 LAST MANUF_PN LTST-C281TBKT-5A
J 0
(-6950 3175);
DISPLAY 0.638298 (-6950 3175);
FORCEPROP 2 LAST COLOR LED_BLUE
J 0
(-6950 3325);
DISPLAY 0.638298 (-6950 3325);
FORCEPROP 0 LAST PACK_TYPE SMLF
J 0
(-6950 3275);
DISPLAY 0.638298 (-6950 3275);
FORCEPROP 1 LAST MATERIAL IC
J 0
(-6825 3275);
DISPLAY 0.723404 (-6825 3275);
PAINT GREEN (-6825 3275);
FORCEPROP 1 LAST NEEDS_NO_SIZE TRUE
J 2
(-6828 3472);
DISPLAY 0.468085 (-6828 3472);
PAINT GREEN (-6828 3472);
DISPLAY INVISIBLE (-6828 3472);
FORCEPROP 2 LAST CDS_LIB pure_quanta
J 0
(-6850 3450);
DISPLAY INVISIBLE (-6850 3450);
FORCEPROP 1 LAST PATH I14
J 2
(-6975 3530);
DISPLAY 0.723404 (-6975 3530);
PAINT GREEN (-6975 3530);
DISPLAY INVISIBLE (-6975 3530);
FORCEPROP 1 LAST PART_NUMBER BEBL0172Z00
J 0
(-6950 3225);
DISPLAY 0.574468 (-6950 3225);
PAINT GREEN (-6950 3225);
DISPLAY INVISIBLE (-6950 3225);
FORCEADD Q_RES..1
(-5475 2125);
FORCEPROP 1 LAST LOCATION R3095
J 0
(-5525 2175);
DISPLAY 0.978723 (-5525 2175);
FORCEPROP 0 LAST $SEC 1
J 0
(-5525 2225);
DISPLAY 0.680851 (-5525 2225);
PAINT MONO (-5525 2225);
DISPLAY INVISIBLE (-5525 2225);
FORCEPROP 0 LAST CDS_SEC 1
J 0
(-5525 2225);
DISPLAY 1.021277 (-5525 2225);
DISPLAY INVISIBLE (-5525 2225);
FORCEPROP 1 LASTPIN (-5575 2125) $PN 1
J 0
(-5563 2137);
DISPLAY 0.787234 (-5563 2137);
PAINT MONO (-5563 2137);
FORCEPROP 1 LASTPIN (-5375 2125) $PN 2
J 0
(-5413 2137);
DISPLAY 0.787234 (-5413 2137);
PAINT MONO (-5413 2137);
FORCEPROP 1 LAST MATERIAL CHIP
J 0
(-5625 2075);
DISPLAY 0.638298 (-5625 2075);
FORCEPROP 1 LAST WATTAGE 1/16W
J 2
(-5325 2075);
DISPLAY 0.638298 (-5325 2075);
FORCEPROP 1 LAST PACK_TYPE 0402LF
J 0
(-5175 2125);
DISPLAY 0.638298 (-5175 2125);
FORCEPROP 1 LAST TOLERANCE 1%
J 0
(-5250 2125);
DISPLAY 0.638298 (-5250 2125);
FORCEPROP 1 LAST VALUE 130
J 2
(-5275 2125);
DISPLAY 0.638298 (-5275 2125);
FORCEPROP 2 LAST CDS_LIB pure_quanta
J 0
(-5475 2125);
DISPLAY INVISIBLE (-5475 2125);
FORCEPROP 1 LAST PATH I15
J 0
(-5525 2275);
DISPLAY 0.978723 (-5525 2275);
PAINT WHITE (-5525 2275);
DISPLAY INVISIBLE (-5525 2275);
FORCEPROP 1 LAST PART_NUMBER CS11302FB03
J 0
(-5700 2225);
DISPLAY 0.638298 (-5700 2225);
DISPLAY INVISIBLE (-5700 2225);
FORCEADD Q_RES..1
(-5425 3450);
FORCEPROP 1 LAST LOCATION R3096
J 0
(-5475 3500);
DISPLAY 0.978723 (-5475 3500);
FORCEPROP 0 LAST $SEC 1
J 0
(-5475 3550);
DISPLAY 0.680851 (-5475 3550);
PAINT MONO (-5475 3550);
DISPLAY INVISIBLE (-5475 3550);
FORCEPROP 0 LAST CDS_SEC 1
J 0
(-5475 3550);
DISPLAY 1.021277 (-5475 3550);
DISPLAY INVISIBLE (-5475 3550);
FORCEPROP 1 LASTPIN (-5525 3450) $PN 1
J 0
(-5513 3462);
DISPLAY 0.787234 (-5513 3462);
PAINT MONO (-5513 3462);
FORCEPROP 1 LASTPIN (-5325 3450) $PN 2
J 0
(-5363 3462);
DISPLAY 0.787234 (-5363 3462);
PAINT MONO (-5363 3462);
FORCEPROP 1 LAST PACK_TYPE 0402LF
J 0
(-5125 3450);
DISPLAY 0.638298 (-5125 3450);
FORCEPROP 1 LAST WATTAGE 1/16W
J 2
(-5275 3400);
DISPLAY 0.638298 (-5275 3400);
FORCEPROP 1 LAST MATERIAL CHIP
J 0
(-5575 3400);
DISPLAY 0.638298 (-5575 3400);
FORCEPROP 1 LAST TOLERANCE 1%
J 0
(-5200 3450);
DISPLAY 0.638298 (-5200 3450);
FORCEPROP 1 LAST VALUE 130
J 2
(-5225 3450);
DISPLAY 0.638298 (-5225 3450);
FORCEPROP 2 LAST CDS_LIB pure_quanta
J 0
(-5425 3450);
DISPLAY INVISIBLE (-5425 3450);
FORCEPROP 1 LAST PATH I16
J 0
(-5475 3600);
DISPLAY 0.978723 (-5475 3600);
PAINT WHITE (-5475 3600);
DISPLAY INVISIBLE (-5475 3600);
FORCEPROP 1 LAST PART_NUMBER CS11302FB03
J 0
(-5650 3550);
DISPLAY 0.638298 (-5650 3550);
DISPLAY INVISIBLE (-5650 3550);
FORCEADD Q_LED..1
R 2
(-6850 4675);
FORCEPROP 1 LAST LOCATION D81
J 0
(-6950 4600);
DISPLAY 0.723404 (-6950 4600);
PAINT GREEN (-6950 4600);
FORCEPROP 0 LAST $SEC 1
J 0
(-6950 4650);
DISPLAY INVISIBLE (-6950 4650);
FORCEPROP 0 LAST CDS_SEC 1
J 0
(-6950 4650);
DISPLAY INVISIBLE (-6950 4650);
FORCEPROP 0 LASTPIN (-6700 4675) $PN A
J 0
(-6690 4685);
DISPLAY 0.808511 (-6690 4685);
FORCEPROP 0 LASTPIN (-7000 4675) $PN C
J 2
(-7010 4685);
DISPLAY 0.808511 (-7010 4685);
FORCEPROP 0 LAST PACK_TYPE SMLF
J 0
(-6950 4500);
DISPLAY 0.638298 (-6950 4500);
FORCEPROP 1 LAST MATERIAL IC
J 0
(-6825 4500);
DISPLAY 0.723404 (-6825 4500);
PAINT GREEN (-6825 4500);
FORCEPROP 2 LAST COLOR LED_BLUE
J 0
(-6950 4550);
DISPLAY 0.638298 (-6950 4550);
FORCEPROP 2 LAST MANUF_PN LTST-C281TBKT-5A
J 0
(-6950 4400);
DISPLAY 0.638298 (-6950 4400);
FORCEPROP 2 LAST CDS_LIB pure_quanta
J 0
(-6850 4675);
DISPLAY INVISIBLE (-6850 4675);
FORCEPROP 1 LAST NEEDS_NO_SIZE TRUE
J 2
(-6828 4697);
DISPLAY 0.468085 (-6828 4697);
PAINT GREEN (-6828 4697);
DISPLAY INVISIBLE (-6828 4697);
FORCEPROP 1 LAST PATH I17
J 2
(-6975 4755);
DISPLAY 0.723404 (-6975 4755);
PAINT GREEN (-6975 4755);
DISPLAY INVISIBLE (-6975 4755);
FORCEPROP 1 LAST PART_NUMBER BEBL0172Z00
J 0
(-6950 4450);
DISPLAY 0.574468 (-6950 4450);
PAINT GREEN (-6950 4450);
DISPLAY INVISIBLE (-6950 4450);
FORCEADD Q_RES..1
(-5475 4675);
FORCEPROP 1 LAST LOCATION R3094
J 0
(-5525 4725);
DISPLAY 0.978723 (-5525 4725);
FORCEPROP 0 LAST $SEC 1
J 0
(-5525 4775);
DISPLAY 0.680851 (-5525 4775);
PAINT MONO (-5525 4775);
DISPLAY INVISIBLE (-5525 4775);
FORCEPROP 0 LAST CDS_SEC 1
J 0
(-5525 4775);
DISPLAY 1.021277 (-5525 4775);
DISPLAY INVISIBLE (-5525 4775);
FORCEPROP 1 LASTPIN (-5575 4675) $PN 1
J 0
(-5563 4687);
DISPLAY 0.787234 (-5563 4687);
PAINT MONO (-5563 4687);
FORCEPROP 1 LASTPIN (-5375 4675) $PN 2
J 0
(-5413 4687);
DISPLAY 0.787234 (-5413 4687);
PAINT MONO (-5413 4687);
FORCEPROP 1 LAST WATTAGE 1/16W
J 2
(-5325 4625);
DISPLAY 0.638298 (-5325 4625);
FORCEPROP 1 LAST MATERIAL CHIP
J 0
(-5625 4625);
DISPLAY 0.638298 (-5625 4625);
FORCEPROP 1 LAST TOLERANCE 1%
J 0
(-5250 4675);
DISPLAY 0.638298 (-5250 4675);
FORCEPROP 1 LAST VALUE 130
J 2
(-5275 4675);
DISPLAY 0.638298 (-5275 4675);
FORCEPROP 1 LAST PACK_TYPE 0402LF
J 0
(-5175 4675);
DISPLAY 0.638298 (-5175 4675);
FORCEPROP 2 LAST CDS_LIB pure_quanta
J 0
(-5475 4675);
DISPLAY INVISIBLE (-5475 4675);
FORCEPROP 1 LAST PATH I18
J 0
(-5525 4825);
DISPLAY 0.978723 (-5525 4825);
PAINT WHITE (-5525 4825);
DISPLAY INVISIBLE (-5525 4825);
FORCEPROP 1 LAST PART_NUMBER CS11302FB03
J 0
(-5700 4775);
DISPLAY 0.638298 (-5700 4775);
DISPLAY INVISIBLE (-5700 4775);
FORCEADD Q_LED..1
R 2
(-6850 6000);
FORCEPROP 1 LAST LOCATION D80
J 0
(-6950 5925);
DISPLAY 0.723404 (-6950 5925);
PAINT GREEN (-6950 5925);
FORCEPROP 0 LAST $SEC 1
J 0
(-6950 5975);
DISPLAY INVISIBLE (-6950 5975);
FORCEPROP 0 LAST CDS_SEC 1
J 0
(-6950 5975);
DISPLAY INVISIBLE (-6950 5975);
FORCEPROP 0 LASTPIN (-6700 6000) $PN A
J 0
(-6690 6010);
DISPLAY 0.808511 (-6690 6010);
FORCEPROP 0 LASTPIN (-7000 6000) $PN C
J 2
(-7010 6010);
DISPLAY 0.808511 (-7010 6010);
FORCEPROP 1 LAST MATERIAL IC
J 0
(-6825 5825);
DISPLAY 0.723404 (-6825 5825);
PAINT GREEN (-6825 5825);
FORCEPROP 2 LAST COLOR LED_BLUE
J 0
(-6950 5875);
DISPLAY 0.638298 (-6950 5875);
FORCEPROP 2 LAST MANUF_PN LTST-C281TBKT-5A
J 0
(-6950 5725);
DISPLAY 0.638298 (-6950 5725);
FORCEPROP 0 LAST PACK_TYPE SMLF
J 0
(-6950 5825);
DISPLAY 0.638298 (-6950 5825);
FORCEPROP 2 LAST CDS_LIB pure_quanta
J 0
(-6850 6000);
DISPLAY INVISIBLE (-6850 6000);
FORCEPROP 1 LAST NEEDS_NO_SIZE TRUE
J 2
(-6828 6022);
DISPLAY 0.468085 (-6828 6022);
PAINT GREEN (-6828 6022);
DISPLAY INVISIBLE (-6828 6022);
FORCEPROP 1 LAST PATH I19
J 2
(-6975 6080);
DISPLAY 0.723404 (-6975 6080);
PAINT GREEN (-6975 6080);
DISPLAY INVISIBLE (-6975 6080);
FORCEPROP 1 LAST PART_NUMBER BEBL0172Z00
J 0
(-6950 5775);
DISPLAY 0.574468 (-6950 5775);
PAINT GREEN (-6950 5775);
DISPLAY INVISIBLE (-6950 5775);
FORCEADD MOSFET_NCH_DUAL..2
(-7925 1850);
FORCEPROP 1 LAST LOCATION Q85
J 0
(-7774 1826);
DISPLAY 0.723404 (-7774 1826);
PAINT AQUA (-7774 1826);
FORCEPROP 2 LAST SEC 2
J 0
(-7750 1975);
DISPLAY 0.680851 (-7750 1975);
PAINT MONO (-7750 1975);
DISPLAY INVISIBLE (-7750 1975);
FORCEPROP 2 LASTPIN (-7875 2050) $PN 3
R 1
J 0
(-7885 2060);
DISPLAY 0.723404 (-7885 2060);
PAINT MONO (-7885 2060);
FORCEPROP 2 LASTPIN (-8125 1800) $PN 5
J 2
(-8135 1810);
DISPLAY 0.723404 (-8135 1810);
PAINT MONO (-8135 1810);
FORCEPROP 2 LASTPIN (-7875 1650) $PN 4
R 1
J 2
(-7885 1640);
DISPLAY 0.723404 (-7885 1640);
PAINT MONO (-7885 1640);
FORCEPROP 2 LAST PART_TYPE SMLF
J 0
(-7750 1925);
DISPLAY 1.021277 (-7750 1925);
FORCEPROP 2 LAST VALUE PJT138K
J 0
(-7750 1875);
DISPLAY 0.723404 (-7750 1875);
PAINT SKYBLUE (-7750 1875);
FORCEPROP 1 LAST MATERIAL IC
J 0
(-7774 1701);
DISPLAY 0.723404 (-7774 1701);
PAINT SKYBLUE (-7774 1701);
FORCEPROP 2 LAST SEC_TYPE 
J 0
(-7750 1975);
DISPLAY 1.021277 (-7750 1975);
DISPLAY INVISIBLE (-7750 1975);
FORCEPROP 2 LAST CDS_LIB pure_quanta
J 0
(-7925 1850);
DISPLAY INVISIBLE (-7925 1850);
FORCEPROP 1 LAST NEEDS_NO_SIZE TRUE
J 0
(-7775 1741);
DISPLAY 0.468085 (-7775 1741);
PAINT GREEN (-7775 1741);
DISPLAY INVISIBLE (-7775 1741);
FORCEPROP 1 LAST CDS_LMAN_SYM_OUTLINE -150,150,150,-150
J 0
(-7925 1850);
DISPLAY 0.468085 (-7925 1850);
PAINT GREEN (-7925 1850);
DISPLAY INVISIBLE (-7925 1850);
FORCEPROP 1 LAST PATH I2
J 0
(-7775 1700);
DISPLAY 0.723404 (-7775 1700);
PAINT GREEN (-7775 1700);
DISPLAY INVISIBLE (-7775 1700);
FORCEPROP 1 LAST PART_NUMBER BAM138K0003
J 0
(-7774 1756);
DISPLAY 0.723404 (-7774 1756);
PAINT BLUE (-7774 1756);
DISPLAY INVISIBLE (-7774 1756);
FORCEADD Q_RES..1
(-5500 6000);
FORCEPROP 1 LAST LOCATION R3093
J 0
(-5550 6050);
DISPLAY 0.978723 (-5550 6050);
FORCEPROP 0 LAST $SEC 1
J 0
(-5550 6100);
DISPLAY 0.680851 (-5550 6100);
PAINT MONO (-5550 6100);
DISPLAY INVISIBLE (-5550 6100);
FORCEPROP 0 LAST CDS_SEC 1
J 0
(-5550 6100);
DISPLAY 1.021277 (-5550 6100);
DISPLAY INVISIBLE (-5550 6100);
FORCEPROP 1 LASTPIN (-5600 6000) $PN 1
J 0
(-5588 6012);
DISPLAY 0.787234 (-5588 6012);
PAINT MONO (-5588 6012);
FORCEPROP 1 LASTPIN (-5400 6000) $PN 2
J 0
(-5438 6012);
DISPLAY 0.787234 (-5438 6012);
PAINT MONO (-5438 6012);
FORCEPROP 1 LAST PACK_TYPE 0402LF
J 0
(-5200 6000);
DISPLAY 0.638298 (-5200 6000);
FORCEPROP 1 LAST WATTAGE 1/16W
J 2
(-5350 5950);
DISPLAY 0.638298 (-5350 5950);
FORCEPROP 1 LAST MATERIAL CHIP
J 0
(-5650 5950);
DISPLAY 0.638298 (-5650 5950);
FORCEPROP 1 LAST TOLERANCE 1%
J 0
(-5275 6000);
DISPLAY 0.638298 (-5275 6000);
FORCEPROP 1 LAST VALUE 130
J 2
(-5300 6000);
DISPLAY 0.638298 (-5300 6000);
FORCEPROP 2 LAST CDS_LIB pure_quanta
J 0
(-5500 6000);
DISPLAY INVISIBLE (-5500 6000);
FORCEPROP 1 LAST PATH I20
J 0
(-5550 6150);
DISPLAY 0.978723 (-5550 6150);
PAINT WHITE (-5550 6150);
DISPLAY INVISIBLE (-5550 6150);
FORCEPROP 1 LAST PART_NUMBER CS11302FB03
J 0
(-5725 6100);
DISPLAY 0.638298 (-5725 6100);
DISPLAY INVISIBLE (-5725 6100);
FORCEADD UNIVERSAL_POWER..1
(-4875 2275);
FORCEPROP 3 LASTPIN (-4875 2225) SIG_NAME P3V3_AUX\g
J 0
(-4865 2235);
DISPLAY 0.659574 (-4865 2235);
PAINT MONO (-4865 2235);
DISPLAY INVISIBLE (-4865 2235);
FORCEPROP 1 LAST HDL_POWER P3V3_AUX
J 1
(-4875 2325);
DISPLAY 0.723404 (-4875 2325);
PAINT GREEN (-4875 2325);
FORCEPROP 2 LAST CDS_LIB pure_quanta_power
J 0
(-4875 2275);
DISPLAY INVISIBLE (-4875 2275);
FORCEPROP 1 LAST PATH I21
J 0
(-4825 2300);
DISPLAY 0.872340 (-4825 2300);
PAINT AQUA (-4825 2300);
DISPLAY INVISIBLE (-4825 2300);
FORCEADD UNIVERSAL_POWER..1
(-4825 3625);
FORCEPROP 3 LASTPIN (-4825 3575) SIG_NAME P3V3_AUX\g
J 0
(-4815 3585);
DISPLAY 0.659574 (-4815 3585);
PAINT MONO (-4815 3585);
DISPLAY INVISIBLE (-4815 3585);
FORCEPROP 1 LAST HDL_POWER P3V3_AUX
J 1
(-4825 3675);
DISPLAY 0.723404 (-4825 3675);
PAINT GREEN (-4825 3675);
FORCEPROP 2 LAST CDS_LIB pure_quanta_power
J 0
(-4825 3625);
DISPLAY INVISIBLE (-4825 3625);
FORCEPROP 1 LAST PATH I22
J 0
(-4775 3650);
DISPLAY 0.872340 (-4775 3650);
PAINT AQUA (-4775 3650);
DISPLAY INVISIBLE (-4775 3650);
FORCEADD OFFPAGE..1
(-4350 4375);
PAINT AQUA (-4350 4375);
FORCEPROP 2 LAST $XR0 80 
J 0
(-4571 4375);
DISPLAY 0.638298 (-4571 4375);
PAINT MONO (-4571 4375);
FORCEPROP 2 LAST CDS_LIB standard
J 0
(-4350 4375);
DISPLAY INVISIBLE (-4350 4375);
FORCEPROP 1 LAST OFFPAGE TRUE
J 0
(-4025 4250);
DISPLAY 0.872340 (-4025 4250);
PAINT AQUA (-4025 4250);
DISPLAY INVISIBLE (-4025 4250);
FORCEPROP 1 LAST COMMENT_BODY TRUE
J 0
(-4225 4275);
DISPLAY 0.872340 (-4225 4275);
PAINT GREEN (-4225 4275);
DISPLAY INVISIBLE (-4225 4275);
FORCEPROP 2 LAST PATH I25
J 0
(-4625 4425);
DISPLAY 0.680851 (-4625 4425);
DISPLAY INVISIBLE (-4625 4425);
FORCEADD UNIVERSAL_POWER..1
(-4875 4800);
FORCEPROP 3 LASTPIN (-4875 4750) SIG_NAME P3V3_AUX\g
J 0
(-4865 4760);
DISPLAY 0.659574 (-4865 4760);
PAINT MONO (-4865 4760);
DISPLAY INVISIBLE (-4865 4760);
FORCEPROP 1 LAST HDL_POWER P3V3_AUX
J 1
(-4875 4850);
DISPLAY 0.723404 (-4875 4850);
PAINT GREEN (-4875 4850);
FORCEPROP 2 LAST CDS_LIB pure_quanta_power
J 0
(-4875 4800);
DISPLAY INVISIBLE (-4875 4800);
FORCEPROP 1 LAST PATH I26
J 0
(-4825 4825);
DISPLAY 0.872340 (-4825 4825);
PAINT AQUA (-4825 4825);
DISPLAY INVISIBLE (-4825 4825);
FORCEADD OFFPAGE..1
(-4350 5700);
PAINT AQUA (-4350 5700);
FORCEPROP 2 LAST $XR0 80 
J 0
(-4571 5700);
DISPLAY 0.638298 (-4571 5700);
PAINT MONO (-4571 5700);
FORCEPROP 2 LAST CDS_LIB standard
J 0
(-4350 5700);
DISPLAY INVISIBLE (-4350 5700);
FORCEPROP 1 LAST OFFPAGE TRUE
J 0
(-4025 5575);
DISPLAY 0.872340 (-4025 5575);
PAINT AQUA (-4025 5575);
DISPLAY INVISIBLE (-4025 5575);
FORCEPROP 1 LAST COMMENT_BODY TRUE
J 0
(-4225 5600);
DISPLAY 0.872340 (-4225 5600);
PAINT GREEN (-4225 5600);
DISPLAY INVISIBLE (-4225 5600);
FORCEPROP 2 LAST PATH I27
J 0
(-4625 5750);
DISPLAY 0.680851 (-4625 5750);
DISPLAY INVISIBLE (-4625 5750);
FORCEADD UNIVERSAL_GND..1
(-3200 4075);
FORCEPROP 3 LASTPIN (-3200 4125) SIG_NAME GND\g
J 0
(-3190 4135);
DISPLAY 0.659574 (-3190 4135);
PAINT MONO (-3190 4135);
DISPLAY INVISIBLE (-3190 4135);
FORCEPROP 2 LAST CDS_LIB pure_quanta_power
J 0
(-3200 4075);
DISPLAY INVISIBLE (-3200 4075);
FORCEPROP 1 LAST HDL_POWER GND
J 1
(-3175 4000);
DISPLAY 0.872340 (-3175 4000);
PAINT GREEN (-3175 4000);
DISPLAY INVISIBLE (-3175 4000);
FORCEPROP 1 LAST PATH I28
J 0
(-3125 4075);
DISPLAY 0.872340 (-3125 4075);
PAINT AQUA (-3125 4075);
DISPLAY INVISIBLE (-3125 4075);
FORCEADD MOSFET_NCH_DUAL..2
(-3250 4425);
FORCEPROP 1 LAST LOCATION Q86
J 0
(-3099 4401);
DISPLAY 0.723404 (-3099 4401);
PAINT AQUA (-3099 4401);
FORCEPROP 2 LAST SEC 2
J 0
(-3075 4550);
DISPLAY 0.680851 (-3075 4550);
PAINT MONO (-3075 4550);
DISPLAY INVISIBLE (-3075 4550);
FORCEPROP 2 LASTPIN (-3200 4625) $PN 3
R 1
J 0
(-3210 4635);
DISPLAY 0.723404 (-3210 4635);
PAINT MONO (-3210 4635);
FORCEPROP 2 LASTPIN (-3450 4375) $PN 5
J 2
(-3460 4385);
DISPLAY 0.723404 (-3460 4385);
PAINT MONO (-3460 4385);
FORCEPROP 2 LASTPIN (-3200 4225) $PN 4
R 1
J 2
(-3210 4215);
DISPLAY 0.723404 (-3210 4215);
PAINT MONO (-3210 4215);
FORCEPROP 2 LAST VALUE PJT138K
J 0
(-3075 4450);
DISPLAY 0.723404 (-3075 4450);
PAINT SKYBLUE (-3075 4450);
FORCEPROP 2 LAST PART_TYPE SMLF
J 0
(-3075 4500);
DISPLAY 1.021277 (-3075 4500);
FORCEPROP 1 LAST MATERIAL IC
J 0
(-3099 4276);
DISPLAY 0.723404 (-3099 4276);
PAINT SKYBLUE (-3099 4276);
FORCEPROP 1 LAST CDS_LMAN_SYM_OUTLINE -150,150,150,-150
J 0
(-3250 4425);
DISPLAY 0.468085 (-3250 4425);
PAINT GREEN (-3250 4425);
DISPLAY INVISIBLE (-3250 4425);
FORCEPROP 2 LAST CDS_LIB pure_quanta
J 0
(-3250 4425);
DISPLAY INVISIBLE (-3250 4425);
FORCEPROP 2 LAST SEC_TYPE 
J 0
(-3075 4550);
DISPLAY 1.021277 (-3075 4550);
DISPLAY INVISIBLE (-3075 4550);
FORCEPROP 1 LAST NEEDS_NO_SIZE TRUE
J 0
(-3100 4316);
DISPLAY 0.468085 (-3100 4316);
PAINT GREEN (-3100 4316);
DISPLAY INVISIBLE (-3100 4316);
FORCEPROP 1 LAST PATH I29
J 0
(-3100 4275);
DISPLAY 0.723404 (-3100 4275);
PAINT GREEN (-3100 4275);
DISPLAY INVISIBLE (-3100 4275);
FORCEPROP 1 LAST PART_NUMBER BAM138K0003
J 0
(-3099 4331);
DISPLAY 0.723404 (-3099 4331);
PAINT BLUE (-3099 4331);
DISPLAY INVISIBLE (-3099 4331);
FORCEADD OFFPAGE..1
(-9025 3125);
PAINT AQUA (-9025 3125);
FORCEPROP 2 LAST $XR0 80 
J 0
(-9276 3125);
DISPLAY 0.638298 (-9276 3125);
PAINT MONO (-9276 3125);
FORCEPROP 2 LAST CDS_LIB standard
J 0
(-9025 3125);
DISPLAY INVISIBLE (-9025 3125);
FORCEPROP 1 LAST OFFPAGE TRUE
J 0
(-8700 3000);
DISPLAY 0.872340 (-8700 3000);
PAINT AQUA (-8700 3000);
DISPLAY INVISIBLE (-8700 3000);
FORCEPROP 1 LAST COMMENT_BODY TRUE
J 0
(-8900 3025);
DISPLAY 0.872340 (-8900 3025);
PAINT GREEN (-8900 3025);
DISPLAY INVISIBLE (-8900 3025);
FORCEPROP 2 LAST PATH I3
J 0
(-9275 3175);
DISPLAY 0.680851 (-9275 3175);
DISPLAY INVISIBLE (-9275 3175);
FORCEADD MOSFET_NCH_DUAL..1
(-3250 5750);
FORCEPROP 1 LAST LOCATION Q86
J 0
(-3099 5724);
DISPLAY 0.723404 (-3099 5724);
PAINT GREEN (-3099 5724);
FORCEPROP 0 LAST $SEC 1
J 0
(-3075 5875);
DISPLAY INVISIBLE (-3075 5875);
FORCEPROP 0 LAST CDS_SEC 1
J 0
(-3075 5875);
DISPLAY INVISIBLE (-3075 5875);
FORCEPROP 0 LASTPIN (-3200 5950) $PN 6
R 1
J 0
(-3210 5960);
DISPLAY 0.808511 (-3210 5960);
FORCEPROP 0 LASTPIN (-3450 5700) $PN 2
J 2
(-3460 5710);
DISPLAY 0.808511 (-3460 5710);
FORCEPROP 0 LASTPIN (-3200 5550) $PN 1
R 1
J 2
(-3210 5540);
DISPLAY 0.808511 (-3210 5540);
FORCEPROP 1 LAST MATERIAL IC
J 0
(-3099 5599);
DISPLAY 0.723404 (-3099 5599);
PAINT GREEN (-3099 5599);
FORCEPROP 2 LAST PART_TYPE SMLF
J 0
(-3075 5825);
DISPLAY 1.021277 (-3075 5825);
FORCEPROP 2 LAST VALUE PJT138K
J 0
(-3075 5775);
DISPLAY 1.021277 (-3075 5775);
FORCEPROP 1 LAST NEEDS_NO_SIZE TRUE
J 0
(-3250 5749);
DISPLAY 0.468085 (-3250 5749);
PAINT GREEN (-3250 5749);
DISPLAY INVISIBLE (-3250 5749);
FORCEPROP 1 LAST CDS_LMAN_SYM_OUTLINE -150,150,150,-150
J 0
(-3250 5750);
DISPLAY 0.468085 (-3250 5750);
PAINT GREEN (-3250 5750);
DISPLAY INVISIBLE (-3250 5750);
FORCEPROP 2 LAST CDS_LIB pure_quanta
J 0
(-3250 5750);
DISPLAY INVISIBLE (-3250 5750);
FORCEPROP 1 LAST PATH I30
J 0
(-3250 5750);
DISPLAY 0.723404 (-3250 5750);
PAINT GREEN (-3250 5750);
DISPLAY INVISIBLE (-3250 5750);
FORCEPROP 1 LAST PART_NUMBER BAM138K0003
J 0
(-3099 5664);
DISPLAY 0.723404 (-3099 5664);
PAINT GREEN (-3099 5664);
DISPLAY INVISIBLE (-3099 5664);
FORCEADD UNIVERSAL_GND..1
(-3200 5400);
FORCEPROP 3 LASTPIN (-3200 5450) SIG_NAME GND\g
J 0
(-3190 5460);
DISPLAY 0.659574 (-3190 5460);
PAINT MONO (-3190 5460);
DISPLAY INVISIBLE (-3190 5460);
FORCEPROP 2 LAST CDS_LIB pure_quanta_power
J 0
(-3200 5400);
DISPLAY INVISIBLE (-3200 5400);
FORCEPROP 1 LAST HDL_POWER GND
J 1
(-3175 5325);
DISPLAY 0.872340 (-3175 5325);
PAINT GREEN (-3175 5325);
DISPLAY INVISIBLE (-3175 5325);
FORCEPROP 1 LAST PATH I31
J 0
(-3125 5400);
DISPLAY 0.872340 (-3125 5400);
PAINT AQUA (-3125 5400);
DISPLAY INVISIBLE (-3125 5400);
FORCEADD Q_LED..1
R 2
(-2175 4700);
FORCEPROP 1 LAST LOCATION D85
J 0
(-2275 4625);
DISPLAY 0.723404 (-2275 4625);
PAINT GREEN (-2275 4625);
FORCEPROP 0 LAST $SEC 1
J 0
(-2275 4675);
DISPLAY INVISIBLE (-2275 4675);
FORCEPROP 0 LAST CDS_SEC 1
J 0
(-2275 4675);
DISPLAY INVISIBLE (-2275 4675);
FORCEPROP 0 LASTPIN (-2025 4700) $PN A
J 0
(-2015 4710);
DISPLAY 0.808511 (-2015 4710);
FORCEPROP 0 LASTPIN (-2325 4700) $PN C
J 2
(-2335 4710);
DISPLAY 0.808511 (-2335 4710);
FORCEPROP 2 LAST MANUF_PN LTST-C281TBKT-5A
J 0
(-2275 4425);
DISPLAY 0.638298 (-2275 4425);
FORCEPROP 2 LAST COLOR LED_BLUE
J 0
(-2275 4575);
DISPLAY 0.638298 (-2275 4575);
FORCEPROP 1 LAST MATERIAL IC
J 0
(-2150 4525);
DISPLAY 0.723404 (-2150 4525);
PAINT GREEN (-2150 4525);
FORCEPROP 0 LAST PACK_TYPE SMLF
J 0
(-2275 4525);
DISPLAY 0.638298 (-2275 4525);
FORCEPROP 2 LAST CDS_LIB pure_quanta
J 0
(-2175 4700);
DISPLAY INVISIBLE (-2175 4700);
FORCEPROP 1 LAST NEEDS_NO_SIZE TRUE
J 2
(-2153 4722);
DISPLAY 0.468085 (-2153 4722);
PAINT GREEN (-2153 4722);
DISPLAY INVISIBLE (-2153 4722);
FORCEPROP 1 LAST PATH I33
J 2
(-2300 4780);
DISPLAY 0.723404 (-2300 4780);
PAINT GREEN (-2300 4780);
DISPLAY INVISIBLE (-2300 4780);
FORCEPROP 1 LAST PART_NUMBER BEBL0172Z00
J 0
(-2275 4475);
DISPLAY 0.574468 (-2275 4475);
PAINT GREEN (-2275 4475);
DISPLAY INVISIBLE (-2275 4475);
FORCEADD UNIVERSAL_POWER..1
(-4850 6150);
FORCEPROP 3 LASTPIN (-4850 6100) SIG_NAME P3V3_AUX\g
J 0
(-4840 6110);
DISPLAY 0.659574 (-4840 6110);
PAINT MONO (-4840 6110);
DISPLAY INVISIBLE (-4840 6110);
FORCEPROP 1 LAST HDL_POWER P3V3_AUX
J 1
(-4850 6200);
DISPLAY 0.723404 (-4850 6200);
PAINT GREEN (-4850 6200);
FORCEPROP 2 LAST CDS_LIB pure_quanta_power
J 0
(-4850 6150);
DISPLAY INVISIBLE (-4850 6150);
FORCEPROP 1 LAST PATH I34
J 0
(-4800 6175);
DISPLAY 0.872340 (-4800 6175);
PAINT AQUA (-4800 6175);
DISPLAY INVISIBLE (-4800 6175);
FORCEADD Q_LED..1
R 2
(-2175 6025);
FORCEPROP 1 LAST LOCATION D84
J 0
(-2275 5950);
DISPLAY 0.723404 (-2275 5950);
PAINT GREEN (-2275 5950);
FORCEPROP 0 LAST $SEC 1
J 0
(-2275 6000);
DISPLAY INVISIBLE (-2275 6000);
FORCEPROP 0 LAST CDS_SEC 1
J 0
(-2275 6000);
DISPLAY INVISIBLE (-2275 6000);
FORCEPROP 0 LASTPIN (-2025 6025) $PN A
J 0
(-2015 6035);
DISPLAY 0.808511 (-2015 6035);
FORCEPROP 0 LASTPIN (-2325 6025) $PN C
J 2
(-2335 6035);
DISPLAY 0.808511 (-2335 6035);
FORCEPROP 2 LAST COLOR LED_BLUE
J 0
(-2275 5900);
DISPLAY 0.638298 (-2275 5900);
FORCEPROP 1 LAST MATERIAL IC
J 0
(-2150 5850);
DISPLAY 0.723404 (-2150 5850);
PAINT GREEN (-2150 5850);
FORCEPROP 2 LAST MANUF_PN LTST-C281TBKT-5A
J 0
(-2275 5750);
DISPLAY 0.638298 (-2275 5750);
FORCEPROP 0 LAST PACK_TYPE SMLF
J 0
(-2275 5850);
DISPLAY 0.638298 (-2275 5850);
FORCEPROP 1 LAST NEEDS_NO_SIZE TRUE
J 2
(-2153 6047);
DISPLAY 0.468085 (-2153 6047);
PAINT GREEN (-2153 6047);
DISPLAY INVISIBLE (-2153 6047);
FORCEPROP 2 LAST CDS_LIB pure_quanta
J 0
(-2175 6025);
DISPLAY INVISIBLE (-2175 6025);
FORCEPROP 1 LAST PATH I35
J 2
(-2300 6105);
DISPLAY 0.723404 (-2300 6105);
PAINT GREEN (-2300 6105);
DISPLAY INVISIBLE (-2300 6105);
FORCEPROP 1 LAST PART_NUMBER BEBL0172Z00
J 0
(-2275 5800);
DISPLAY 0.574468 (-2275 5800);
PAINT GREEN (-2275 5800);
DISPLAY INVISIBLE (-2275 5800);
FORCEADD Q_RES..1
(-875 4700);
FORCEPROP 1 LAST LOCATION R3097
J 0
(-925 4750);
DISPLAY 0.978723 (-925 4750);
FORCEPROP 0 LAST $SEC 1
J 0
(-925 4800);
DISPLAY 0.680851 (-925 4800);
PAINT MONO (-925 4800);
DISPLAY INVISIBLE (-925 4800);
FORCEPROP 0 LAST CDS_SEC 1
J 0
(-925 4800);
DISPLAY 1.021277 (-925 4800);
DISPLAY INVISIBLE (-925 4800);
FORCEPROP 1 LASTPIN (-975 4700) $PN 1
J 0
(-963 4712);
DISPLAY 0.787234 (-963 4712);
PAINT MONO (-963 4712);
FORCEPROP 1 LASTPIN (-775 4700) $PN 2
J 0
(-813 4712);
DISPLAY 0.787234 (-813 4712);
PAINT MONO (-813 4712);
FORCEPROP 1 LAST PACK_TYPE 0402LF
J 0
(-575 4700);
DISPLAY 0.638298 (-575 4700);
FORCEPROP 1 LAST WATTAGE 1/16W
J 2
(-725 4650);
DISPLAY 0.638298 (-725 4650);
FORCEPROP 1 LAST MATERIAL CHIP
J 0
(-1025 4650);
DISPLAY 0.638298 (-1025 4650);
FORCEPROP 1 LAST TOLERANCE 1%
J 0
(-650 4700);
DISPLAY 0.638298 (-650 4700);
FORCEPROP 1 LAST VALUE 130
J 2
(-675 4700);
DISPLAY 0.638298 (-675 4700);
FORCEPROP 2 LAST CDS_LIB pure_quanta
J 0
(-875 4700);
DISPLAY INVISIBLE (-875 4700);
FORCEPROP 1 LAST PATH I38
J 0
(-925 4850);
DISPLAY 0.978723 (-925 4850);
PAINT WHITE (-925 4850);
DISPLAY INVISIBLE (-925 4850);
FORCEPROP 1 LAST PART_NUMBER CS11302FB03
J 0
(-1100 4800);
DISPLAY 0.638298 (-1100 4800);
DISPLAY INVISIBLE (-1100 4800);
FORCEADD UNIVERSAL_POWER..1
(-225 4850);
FORCEPROP 3 LASTPIN (-225 4800) SIG_NAME P3V3_AUX\g
J 0
(-215 4810);
DISPLAY 0.659574 (-215 4810);
PAINT MONO (-215 4810);
DISPLAY INVISIBLE (-215 4810);
FORCEPROP 1 LAST HDL_POWER P3V3_AUX
J 1
(-225 4900);
DISPLAY 0.723404 (-225 4900);
PAINT GREEN (-225 4900);
FORCEPROP 2 LAST CDS_LIB pure_quanta_power
J 0
(-225 4850);
DISPLAY INVISIBLE (-225 4850);
FORCEPROP 1 LAST PATH I39
J 0
(-175 4875);
DISPLAY 0.872340 (-175 4875);
PAINT AQUA (-175 4875);
DISPLAY INVISIBLE (-175 4875);
FORCEADD OFFPAGE..1
(-9025 1800);
PAINT AQUA (-9025 1800);
FORCEPROP 2 LAST $XR0 80 
J 0
(-9276 1800);
DISPLAY 0.638298 (-9276 1800);
PAINT MONO (-9276 1800);
FORCEPROP 2 LAST CDS_LIB standard
J 0
(-9025 1800);
DISPLAY INVISIBLE (-9025 1800);
FORCEPROP 1 LAST OFFPAGE TRUE
J 0
(-8700 1675);
DISPLAY 0.872340 (-8700 1675);
PAINT AQUA (-8700 1675);
DISPLAY INVISIBLE (-8700 1675);
FORCEPROP 1 LAST COMMENT_BODY TRUE
J 0
(-8900 1700);
DISPLAY 0.872340 (-8900 1700);
PAINT GREEN (-8900 1700);
DISPLAY INVISIBLE (-8900 1700);
FORCEPROP 2 LAST PATH I4
J 0
(-9275 1850);
DISPLAY 0.680851 (-9275 1850);
DISPLAY INVISIBLE (-9275 1850);
FORCEADD Q_RES..1
(-850 6025);
FORCEPROP 1 LAST LOCATION R3099
J 0
(-900 6075);
DISPLAY 0.978723 (-900 6075);
FORCEPROP 0 LAST $SEC 1
J 0
(-900 6125);
DISPLAY 0.680851 (-900 6125);
PAINT MONO (-900 6125);
DISPLAY INVISIBLE (-900 6125);
FORCEPROP 0 LAST CDS_SEC 1
J 0
(-900 6125);
DISPLAY 1.021277 (-900 6125);
DISPLAY INVISIBLE (-900 6125);
FORCEPROP 1 LASTPIN (-950 6025) $PN 1
J 0
(-938 6037);
DISPLAY 0.787234 (-938 6037);
PAINT MONO (-938 6037);
FORCEPROP 1 LASTPIN (-750 6025) $PN 2
J 0
(-788 6037);
DISPLAY 0.787234 (-788 6037);
PAINT MONO (-788 6037);
FORCEPROP 1 LAST PACK_TYPE 0402LF
J 0
(-550 6025);
DISPLAY 0.638298 (-550 6025);
FORCEPROP 1 LAST WATTAGE 1/16W
J 2
(-700 5975);
DISPLAY 0.638298 (-700 5975);
FORCEPROP 1 LAST MATERIAL CHIP
J 0
(-1000 5975);
DISPLAY 0.638298 (-1000 5975);
FORCEPROP 1 LAST TOLERANCE 1%
J 0
(-625 6025);
DISPLAY 0.638298 (-625 6025);
FORCEPROP 1 LAST VALUE 130
J 2
(-650 6025);
DISPLAY 0.638298 (-650 6025);
FORCEPROP 2 LAST CDS_LIB pure_quanta
J 0
(-850 6025);
DISPLAY INVISIBLE (-850 6025);
FORCEPROP 1 LAST PATH I40
J 0
(-900 6175);
DISPLAY 0.978723 (-900 6175);
PAINT WHITE (-900 6175);
DISPLAY INVISIBLE (-900 6175);
FORCEPROP 1 LAST PART_NUMBER CS11302FB03
J 0
(-1075 6125);
DISPLAY 0.638298 (-1075 6125);
DISPLAY INVISIBLE (-1075 6125);
FORCEADD UNIVERSAL_POWER..1
(-250 6200);
FORCEPROP 3 LASTPIN (-250 6150) SIG_NAME P3V3_AUX\g
J 0
(-240 6160);
DISPLAY 0.659574 (-240 6160);
PAINT MONO (-240 6160);
DISPLAY INVISIBLE (-240 6160);
FORCEPROP 1 LAST HDL_POWER P3V3_AUX
J 1
(-250 6250);
DISPLAY 0.723404 (-250 6250);
PAINT GREEN (-250 6250);
FORCEPROP 2 LAST CDS_LIB pure_quanta_power
J 0
(-250 6200);
DISPLAY INVISIBLE (-250 6200);
FORCEPROP 1 LAST PATH I41
J 0
(-200 6225);
DISPLAY 0.872340 (-200 6225);
PAINT AQUA (-200 6225);
DISPLAY INVISIBLE (-200 6225);
FORCEADD Q_LED..1
R 2
(-4100 3575);
FORCEPROP 1 LAST LOCATION D8000
J 2
(-3825 3330);
DISPLAY 0.723404 (-3825 3330);
PAINT GREEN (-3825 3330);
FORCEPROP 2 LAST SEC 1
J 0
(-4000 3950);
DISPLAY 0.680851 (-4000 3950);
PAINT MONO (-4000 3950);
DISPLAY INVISIBLE (-4000 3950);
FORCEPROP 2 LASTPIN (-3950 3575) $PN A
J 0
(-3940 3585);
DISPLAY 0.680851 (-3940 3585);
PAINT MONO (-3940 3585);
FORCEPROP 2 LASTPIN (-4250 3575) $PN C
J 2
(-4260 3585);
DISPLAY 0.680851 (-4260 3585);
PAINT MONO (-4260 3585);
FORCEPROP 2 LAST PACK_TYPE SMLF
J 2
(-3825 3370);
DISPLAY 0.680851 (-3825 3370);
FORCEPROP 1 LAST MATERIAL IC
J 2
(-3825 3225);
DISPLAY 0.723404 (-3825 3225);
PAINT GREEN (-3825 3225);
FORCEPROP 2 LAST COLOR LED_BLUE
J 2
(-3825 3470);
DISPLAY 0.680851 (-3825 3470);
FORCEPROP 2 LAST MANUF_PN LTST-C281TBKT-5A
J 2
(-3825 3420);
DISPLAY 0.680851 (-3825 3420);
FORCEPROP 2 LAST SEC_TYPE SMLF
J 0
(-4000 3950);
DISPLAY 0.680851 (-4000 3950);
DISPLAY INVISIBLE (-4000 3950);
FORCEPROP 1 LAST NEEDS_NO_SIZE TRUE
J 2
(-4100 3575);
DISPLAY 0.468085 (-4100 3575);
PAINT GREEN (-4100 3575);
DISPLAY INVISIBLE (-4100 3575);
FORCEPROP 2 LAST CDS_LIB pure_quanta
J 2
(-4100 3575);
DISPLAY INVISIBLE (-4100 3575);
FORCEPROP 1 LAST PATH I42
J 2
(-4225 3655);
DISPLAY 0.723404 (-4225 3655);
PAINT GREEN (-4225 3655);
DISPLAY INVISIBLE (-4225 3655);
FORCEPROP 1 LAST PART_NUMBER BEBL0172Z00
J 2
(-3825 3280);
DISPLAY 0.723404 (-3825 3280);
PAINT GREEN (-3825 3280);
DISPLAY INVISIBLE (-3825 3280);
FORCEADD UNIVERSAL_GND..1
(-4525 3375);
FORCEPROP 3 LASTPIN (-4525 3425) SIG_NAME GND\g
J 0
(-4515 3435);
DISPLAY 0.659574 (-4515 3435);
PAINT MONO (-4515 3435);
DISPLAY INVISIBLE (-4515 3435);
FORCEPROP 2 LAST CDS_LIB pure_quanta_power
J 0
(-4525 3375);
DISPLAY INVISIBLE (-4525 3375);
FORCEPROP 1 LAST HDL_POWER GND
J 1
(-4500 3300);
DISPLAY 0.872340 (-4500 3300);
PAINT GREEN (-4500 3300);
DISPLAY INVISIBLE (-4500 3300);
FORCEPROP 1 LAST PATH I43
J 0
(-4450 3375);
DISPLAY 0.872340 (-4450 3375);
PAINT AQUA (-4450 3375);
DISPLAY INVISIBLE (-4450 3375);
FORCEADD Q_RES..1
(-3000 3575);
FORCEPROP 1 LAST LOCATION R8022
J 0
(-3050 3650);
DISPLAY 1.021277 (-3050 3650);
FORCEPROP 2 LAST SEC 1
J 0
(-3050 3775);
DISPLAY 0.680851 (-3050 3775);
PAINT MONO (-3050 3775);
DISPLAY INVISIBLE (-3050 3775);
FORCEPROP 1 LASTPIN (-3100 3575) $PN 1
J 0
(-3088 3587);
DISPLAY 0.787234 (-3088 3587);
PAINT MONO (-3088 3587);
FORCEPROP 1 LASTPIN (-2900 3575) $PN 2
J 0
(-2938 3587);
DISPLAY 0.787234 (-2938 3587);
PAINT MONO (-2938 3587);
FORCEPROP 1 LAST PACK_TYPE 0402LF
J 0
(-2850 3475);
DISPLAY 0.638298 (-2850 3475);
FORCEPROP 1 LAST MATERIAL CHIP
J 0
(-3000 3475);
DISPLAY 0.638298 (-3000 3475);
FORCEPROP 1 LAST VALUE 560
J 2
(-3125 3525);
DISPLAY 0.638298 (-3125 3525);
FORCEPROP 1 LAST TOLERANCE 1%
J 0
(-3075 3525);
DISPLAY 0.638298 (-3075 3525);
FORCEPROP 1 LAST WATTAGE 1/16W
J 2
(-3050 3475);
DISPLAY 0.638298 (-3050 3475);
FORCEPROP 2 LAST SEC_TYPE 0402LF
J 0
(-3050 3775);
DISPLAY 0.680851 (-3050 3775);
DISPLAY INVISIBLE (-3050 3775);
FORCEPROP 2 LAST CDS_LIB pure_quanta
J 0
(-3000 3575);
DISPLAY INVISIBLE (-3000 3575);
FORCEPROP 1 LAST PATH I44
J 0
(-3050 3725);
DISPLAY 0.978723 (-3050 3725);
PAINT WHITE (-3050 3725);
DISPLAY INVISIBLE (-3050 3725);
FORCEPROP 1 LAST PART_NUMBER CS15602FB03
J 0
(-2975 3525);
DISPLAY 0.638298 (-2975 3525);
DISPLAY INVISIBLE (-2975 3525);
FORCEADD Q_RES..1
(-2075 3575);
FORCEPROP 1 LAST LOCATION R8023
J 0
(-2125 3625);
DISPLAY 0.978723 (-2125 3625);
FORCEPROP 2 LAST SEC 1
J 0
(-2125 3775);
DISPLAY 0.680851 (-2125 3775);
PAINT MONO (-2125 3775);
DISPLAY INVISIBLE (-2125 3775);
FORCEPROP 1 LASTPIN (-2175 3575) $PN 1
J 0
(-2163 3587);
DISPLAY 0.787234 (-2163 3587);
PAINT MONO (-2163 3587);
FORCEPROP 1 LASTPIN (-1975 3575) $PN 2
J 0
(-2013 3587);
DISPLAY 0.787234 (-2013 3587);
PAINT MONO (-2013 3587);
FORCEPROP 1 LAST TOLERANCE 1%
J 0
(-2150 3525);
DISPLAY 0.638298 (-2150 3525);
FORCEPROP 1 LAST MATERIAL CHIP
J 0
(-2075 3475);
DISPLAY 0.638298 (-2075 3475);
FORCEPROP 1 LAST PACK_TYPE 0402LF
J 0
(-1925 3475);
DISPLAY 0.638298 (-1925 3475);
FORCEPROP 1 LAST VALUE 560
J 2
(-2200 3525);
DISPLAY 0.638298 (-2200 3525);
FORCEPROP 1 LAST WATTAGE 1/16W
J 2
(-2125 3475);
DISPLAY 0.638298 (-2125 3475);
FORCEPROP 2 LAST SEC_TYPE 0402LF
J 0
(-2125 3775);
DISPLAY 0.680851 (-2125 3775);
DISPLAY INVISIBLE (-2125 3775);
FORCEPROP 2 LAST CDS_LIB pure_quanta
J 0
(-2075 3575);
DISPLAY INVISIBLE (-2075 3575);
FORCEPROP 1 LAST PATH I45
J 0
(-2125 3725);
DISPLAY 0.978723 (-2125 3725);
PAINT WHITE (-2125 3725);
DISPLAY INVISIBLE (-2125 3725);
FORCEPROP 1 LAST PART_NUMBER CS15602FB03
J 0
(-2050 3525);
DISPLAY 0.638298 (-2050 3525);
DISPLAY INVISIBLE (-2050 3525);
FORCEADD Q_RES..1
(-1075 3575);
FORCEPROP 1 LAST LOCATION R8024
J 0
(-1125 3625);
DISPLAY 0.978723 (-1125 3625);
FORCEPROP 2 LAST SEC 1
J 0
(-1125 3775);
DISPLAY 0.680851 (-1125 3775);
PAINT MONO (-1125 3775);
DISPLAY INVISIBLE (-1125 3775);
FORCEPROP 1 LASTPIN (-1175 3575) $PN 1
J 0
(-1163 3587);
DISPLAY 0.787234 (-1163 3587);
PAINT MONO (-1163 3587);
FORCEPROP 1 LASTPIN (-975 3575) $PN 2
J 0
(-1013 3587);
DISPLAY 0.787234 (-1013 3587);
PAINT MONO (-1013 3587);
FORCEPROP 1 LAST PACK_TYPE 0402LF
J 0
(-925 3475);
DISPLAY 0.638298 (-925 3475);
FORCEPROP 1 LAST MATERIAL CHIP
J 0
(-1075 3475);
DISPLAY 0.638298 (-1075 3475);
FORCEPROP 1 LAST TOLERANCE 1%
J 0
(-1150 3525);
DISPLAY 0.638298 (-1150 3525);
FORCEPROP 1 LAST VALUE 560
J 2
(-1200 3525);
DISPLAY 0.638298 (-1200 3525);
FORCEPROP 1 LAST WATTAGE 1/16W
J 2
(-1125 3475);
DISPLAY 0.638298 (-1125 3475);
FORCEPROP 2 LAST SEC_TYPE 0402LF
J 0
(-1125 3775);
DISPLAY 0.680851 (-1125 3775);
DISPLAY INVISIBLE (-1125 3775);
FORCEPROP 2 LAST CDS_LIB pure_quanta
J 0
(-1075 3575);
DISPLAY INVISIBLE (-1075 3575);
FORCEPROP 1 LAST PATH I46
J 0
(-1125 3725);
DISPLAY 0.978723 (-1125 3725);
PAINT WHITE (-1125 3725);
DISPLAY INVISIBLE (-1125 3725);
FORCEPROP 1 LAST PART_NUMBER CS15602FB03
J 0
(-1050 3525);
DISPLAY 0.638298 (-1050 3525);
DISPLAY INVISIBLE (-1050 3525);
FORCEADD UNIVERSAL_POWER..1
(-775 3825);
FORCEPROP 3 LASTPIN (-775 3775) SIG_NAME P12V_AUX\g
J 0
(-765 3785);
DISPLAY 0.659574 (-765 3785);
PAINT MONO (-765 3785);
DISPLAY INVISIBLE (-765 3785);
FORCEPROP 1 LAST HDL_POWER P12V_AUX
J 1
(-775 3875);
DISPLAY 0.872340 (-775 3875);
PAINT GREEN (-775 3875);
FORCEPROP 2 LAST CDS_LIB pure_quanta_power
J 0
(-775 3825);
DISPLAY INVISIBLE (-775 3825);
FORCEPROP 1 LAST PATH I47
J 0
(-725 3850);
DISPLAY 0.872340 (-725 3850);
PAINT AQUA (-725 3850);
DISPLAY INVISIBLE (-725 3850);
FORCEADD UNIVERSAL_POWER..1
(-700 2675);
FORCEPROP 3 LASTPIN (-700 2625) SIG_NAME P12V_PSU\g
J 0
(-690 2635);
DISPLAY 0.659574 (-690 2635);
PAINT MONO (-690 2635);
DISPLAY INVISIBLE (-690 2635);
FORCEPROP 1 LAST HDL_POWER P12V_PSU
J 1
(-700 2725);
DISPLAY 0.872340 (-700 2725);
PAINT GREEN (-700 2725);
FORCEPROP 2 LAST CDS_LIB pure_quanta_power
J 0
(-700 2675);
DISPLAY INVISIBLE (-700 2675);
FORCEPROP 1 LAST PATH I48
J 0
(-650 2700);
DISPLAY 0.872340 (-650 2700);
PAINT AQUA (-650 2700);
DISPLAY INVISIBLE (-650 2700);
FORCEADD Q_RES..1
(-1000 2425);
FORCEPROP 1 LAST LOCATION R8027
J 0
(-1050 2475);
DISPLAY 0.978723 (-1050 2475);
FORCEPROP 2 LAST SEC 1
J 0
(-1050 2625);
DISPLAY 0.680851 (-1050 2625);
PAINT MONO (-1050 2625);
DISPLAY INVISIBLE (-1050 2625);
FORCEPROP 1 LASTPIN (-1100 2425) $PN 1
J 0
(-1088 2437);
DISPLAY 0.787234 (-1088 2437);
PAINT MONO (-1088 2437);
FORCEPROP 1 LASTPIN (-900 2425) $PN 2
J 0
(-938 2437);
DISPLAY 0.787234 (-938 2437);
PAINT MONO (-938 2437);
FORCEPROP 1 LAST PACK_TYPE 0402LF
J 0
(-850 2325);
DISPLAY 0.638298 (-850 2325);
FORCEPROP 1 LAST TOLERANCE 1%
J 0
(-1075 2375);
DISPLAY 0.638298 (-1075 2375);
FORCEPROP 1 LAST VALUE 560
J 2
(-1125 2375);
DISPLAY 0.638298 (-1125 2375);
FORCEPROP 1 LAST MATERIAL CHIP
J 0
(-1000 2325);
DISPLAY 0.638298 (-1000 2325);
FORCEPROP 1 LAST WATTAGE 1/16W
J 2
(-1050 2325);
DISPLAY 0.638298 (-1050 2325);
FORCEPROP 2 LAST SEC_TYPE 0402LF
J 0
(-1050 2625);
DISPLAY 0.680851 (-1050 2625);
DISPLAY INVISIBLE (-1050 2625);
FORCEPROP 2 LAST CDS_LIB pure_quanta
J 0
(-1000 2425);
DISPLAY INVISIBLE (-1000 2425);
FORCEPROP 1 LAST PATH I49
J 0
(-1050 2575);
DISPLAY 0.978723 (-1050 2575);
PAINT WHITE (-1050 2575);
DISPLAY INVISIBLE (-1050 2575);
FORCEPROP 1 LAST PART_NUMBER CS15602FB03
J 0
(-975 2375);
DISPLAY 0.638298 (-975 2375);
DISPLAY INVISIBLE (-975 2375);
FORCEADD OFFPAGE..1
(-9025 5675);
PAINT AQUA (-9025 5675);
FORCEPROP 2 LAST $XR0 81 
J 0
(-9276 5675);
DISPLAY 0.638298 (-9276 5675);
PAINT MONO (-9276 5675);
FORCEPROP 2 LAST CDS_LIB standard
J 0
(-9025 5675);
DISPLAY INVISIBLE (-9025 5675);
FORCEPROP 1 LAST OFFPAGE TRUE
J 0
(-8700 5550);
DISPLAY 0.872340 (-8700 5550);
PAINT AQUA (-8700 5550);
DISPLAY INVISIBLE (-8700 5550);
FORCEPROP 1 LAST COMMENT_BODY TRUE
J 0
(-8900 5575);
DISPLAY 0.872340 (-8900 5575);
PAINT GREEN (-8900 5575);
DISPLAY INVISIBLE (-8900 5575);
FORCEPROP 2 LAST PATH I5
J 0
(-9275 5725);
DISPLAY 0.680851 (-9275 5725);
DISPLAY INVISIBLE (-9275 5725);
FORCEADD Q_RES..1
(-2000 2425);
FORCEPROP 1 LAST LOCATION R8026
J 0
(-2050 2475);
DISPLAY 0.978723 (-2050 2475);
FORCEPROP 2 LAST SEC 1
J 0
(-2050 2625);
DISPLAY 0.680851 (-2050 2625);
PAINT MONO (-2050 2625);
DISPLAY INVISIBLE (-2050 2625);
FORCEPROP 1 LASTPIN (-2100 2425) $PN 1
J 0
(-2088 2437);
DISPLAY 0.787234 (-2088 2437);
PAINT MONO (-2088 2437);
FORCEPROP 1 LASTPIN (-1900 2425) $PN 2
J 0
(-1938 2437);
DISPLAY 0.787234 (-1938 2437);
PAINT MONO (-1938 2437);
FORCEPROP 1 LAST WATTAGE 1/16W
J 2
(-2050 2325);
DISPLAY 0.638298 (-2050 2325);
FORCEPROP 1 LAST PACK_TYPE 0402LF
J 0
(-1850 2325);
DISPLAY 0.638298 (-1850 2325);
FORCEPROP 1 LAST TOLERANCE 1%
J 0
(-2075 2375);
DISPLAY 0.638298 (-2075 2375);
FORCEPROP 1 LAST VALUE 560
J 2
(-2125 2375);
DISPLAY 0.638298 (-2125 2375);
FORCEPROP 1 LAST MATERIAL CHIP
J 0
(-2000 2325);
DISPLAY 0.638298 (-2000 2325);
FORCEPROP 2 LAST SEC_TYPE 0402LF
J 0
(-2050 2625);
DISPLAY 0.680851 (-2050 2625);
DISPLAY INVISIBLE (-2050 2625);
FORCEPROP 2 LAST CDS_LIB pure_quanta
J 0
(-2000 2425);
DISPLAY INVISIBLE (-2000 2425);
FORCEPROP 1 LAST PATH I50
J 0
(-2050 2575);
DISPLAY 0.978723 (-2050 2575);
PAINT WHITE (-2050 2575);
DISPLAY INVISIBLE (-2050 2575);
FORCEPROP 1 LAST PART_NUMBER CS15602FB03
J 0
(-1975 2375);
DISPLAY 0.638298 (-1975 2375);
DISPLAY INVISIBLE (-1975 2375);
FORCEADD Q_RES..1
(-2925 2425);
FORCEPROP 1 LAST LOCATION R8025
J 0
(-2975 2500);
DISPLAY 1.021277 (-2975 2500);
FORCEPROP 2 LAST SEC 1
J 0
(-2975 2625);
DISPLAY 0.680851 (-2975 2625);
PAINT MONO (-2975 2625);
DISPLAY INVISIBLE (-2975 2625);
FORCEPROP 1 LASTPIN (-3025 2425) $PN 1
J 0
(-3013 2437);
DISPLAY 0.787234 (-3013 2437);
PAINT MONO (-3013 2437);
FORCEPROP 1 LASTPIN (-2825 2425) $PN 2
J 0
(-2863 2437);
DISPLAY 0.787234 (-2863 2437);
PAINT MONO (-2863 2437);
FORCEPROP 1 LAST PACK_TYPE 0402LF
J 0
(-2775 2325);
DISPLAY 0.638298 (-2775 2325);
FORCEPROP 1 LAST TOLERANCE 1%
J 0
(-3000 2375);
DISPLAY 0.638298 (-3000 2375);
FORCEPROP 1 LAST WATTAGE 1/16W
J 2
(-2975 2325);
DISPLAY 0.638298 (-2975 2325);
FORCEPROP 1 LAST VALUE 560
J 2
(-3050 2375);
DISPLAY 0.638298 (-3050 2375);
FORCEPROP 1 LAST MATERIAL CHIP
J 0
(-2925 2325);
DISPLAY 0.638298 (-2925 2325);
FORCEPROP 2 LAST SEC_TYPE 0402LF
J 0
(-2975 2625);
DISPLAY 0.680851 (-2975 2625);
DISPLAY INVISIBLE (-2975 2625);
FORCEPROP 2 LAST CDS_LIB pure_quanta
J 0
(-2925 2425);
DISPLAY INVISIBLE (-2925 2425);
FORCEPROP 1 LAST PATH I51
J 0
(-2975 2575);
DISPLAY 0.978723 (-2975 2575);
PAINT WHITE (-2975 2575);
DISPLAY INVISIBLE (-2975 2575);
FORCEPROP 1 LAST PART_NUMBER CS15602FB03
J 0
(-2900 2375);
DISPLAY 0.638298 (-2900 2375);
DISPLAY INVISIBLE (-2900 2375);
FORCEADD Q_LED..1
R 2
(-4025 2425);
FORCEPROP 1 LAST LOCATION D8001
J 2
(-3750 2180);
DISPLAY 0.723404 (-3750 2180);
PAINT GREEN (-3750 2180);
FORCEPROP 2 LAST SEC 1
J 0
(-3925 2800);
DISPLAY 0.680851 (-3925 2800);
PAINT MONO (-3925 2800);
DISPLAY INVISIBLE (-3925 2800);
FORCEPROP 2 LASTPIN (-3875 2425) $PN A
J 0
(-3865 2435);
DISPLAY 0.680851 (-3865 2435);
PAINT MONO (-3865 2435);
FORCEPROP 2 LASTPIN (-4175 2425) $PN C
J 2
(-4185 2435);
DISPLAY 0.680851 (-4185 2435);
PAINT MONO (-4185 2435);
FORCEPROP 2 LAST PACK_TYPE SMLF
J 2
(-3750 2220);
DISPLAY 0.680851 (-3750 2220);
FORCEPROP 2 LAST MANUF_PN LTST-C281TBKT-5A
J 2
(-3750 2270);
DISPLAY 0.680851 (-3750 2270);
FORCEPROP 1 LAST MATERIAL IC
J 2
(-3750 2075);
DISPLAY 0.723404 (-3750 2075);
PAINT GREEN (-3750 2075);
FORCEPROP 2 LAST COLOR LED_BLUE
J 2
(-3750 2320);
DISPLAY 0.680851 (-3750 2320);
FORCEPROP 2 LAST SEC_TYPE SMLF
J 0
(-3925 2800);
DISPLAY 0.680851 (-3925 2800);
DISPLAY INVISIBLE (-3925 2800);
FORCEPROP 1 LAST NEEDS_NO_SIZE TRUE
J 2
(-4025 2425);
DISPLAY 0.468085 (-4025 2425);
PAINT GREEN (-4025 2425);
DISPLAY INVISIBLE (-4025 2425);
FORCEPROP 2 LAST CDS_LIB pure_quanta
J 2
(-4025 2425);
DISPLAY INVISIBLE (-4025 2425);
FORCEPROP 1 LAST PATH I52
J 2
(-4150 2505);
DISPLAY 0.723404 (-4150 2505);
PAINT GREEN (-4150 2505);
DISPLAY INVISIBLE (-4150 2505);
FORCEPROP 1 LAST PART_NUMBER BEBL0172Z00
J 2
(-3750 2130);
DISPLAY 0.723404 (-3750 2130);
PAINT GREEN (-3750 2130);
DISPLAY INVISIBLE (-3750 2130);
FORCEADD UNIVERSAL_GND..1
(-4450 2225);
FORCEPROP 3 LASTPIN (-4450 2275) SIG_NAME GND\g
J 0
(-4440 2285);
DISPLAY 0.659574 (-4440 2285);
PAINT MONO (-4440 2285);
DISPLAY INVISIBLE (-4440 2285);
FORCEPROP 2 LAST CDS_LIB pure_quanta_power
J 0
(-4450 2225);
DISPLAY INVISIBLE (-4450 2225);
FORCEPROP 1 LAST HDL_POWER GND
J 1
(-4425 2150);
DISPLAY 0.872340 (-4425 2150);
PAINT GREEN (-4425 2150);
DISPLAY INVISIBLE (-4425 2150);
FORCEPROP 1 LAST PATH I53
J 0
(-4375 2225);
DISPLAY 0.872340 (-4375 2225);
PAINT AQUA (-4375 2225);
DISPLAY INVISIBLE (-4375 2225);
FORCEADD UNIVERSAL_POWER..1
(-325 1750);
FORCEPROP 3 LASTPIN (-325 1700) SIG_NAME P3V3_AUX\g
J 0
(-315 1710);
DISPLAY 0.659574 (-315 1710);
PAINT MONO (-315 1710);
DISPLAY INVISIBLE (-315 1710);
FORCEPROP 1 LAST HDL_POWER P3V3_AUX
J 1
(-325 1800);
DISPLAY 0.723404 (-325 1800);
PAINT GREEN (-325 1800);
FORCEPROP 2 LAST CDS_LIB pure_quanta_power
J 0
(-325 1750);
DISPLAY INVISIBLE (-325 1750);
FORCEPROP 1 LAST PATH I54
J 0
(-275 1775);
DISPLAY 0.872340 (-275 1775);
PAINT AQUA (-275 1775);
DISPLAY INVISIBLE (-275 1775);
FORCEADD Q_RES..1
(-775 1500);
FORCEPROP 1 LAST LOCATION R8029
J 0
(-825 1650);
DISPLAY 0.978723 (-825 1650);
FORCEPROP 2 LAST SEC 1
J 0
(-825 1700);
DISPLAY 0.680851 (-825 1700);
PAINT MONO (-825 1700);
DISPLAY INVISIBLE (-825 1700);
FORCEPROP 1 LASTPIN (-875 1500) $PN 1
J 0
(-863 1512);
DISPLAY 0.787234 (-863 1512);
PAINT MONO (-863 1512);
FORCEPROP 1 LASTPIN (-675 1500) $PN 2
J 0
(-713 1512);
DISPLAY 0.787234 (-713 1512);
PAINT MONO (-713 1512);
FORCEPROP 1 LAST WATTAGE 1/16W
J 2
(-800 1350);
DISPLAY 0.787234 (-800 1350);
FORCEPROP 1 LAST VALUE 249
J 2
(-800 1400);
DISPLAY 0.787234 (-800 1400);
FORCEPROP 1 LAST MATERIAL CHIP
J 0
(-775 1350);
DISPLAY 0.787234 (-775 1350);
FORCEPROP 1 LAST TOLERANCE 1%
J 0
(-775 1400);
DISPLAY 0.787234 (-775 1400);
FORCEPROP 1 LAST PACK_TYPE 0402LF
J 0
(-525 1350);
DISPLAY 0.787234 (-525 1350);
FORCEPROP 2 LAST CDS_LIB pure_quanta
J 0
(-775 1500);
DISPLAY INVISIBLE (-775 1500);
FORCEPROP 2 LAST SEC_TYPE 0402LF
J 0
(-825 1700);
DISPLAY 0.680851 (-825 1700);
DISPLAY INVISIBLE (-825 1700);
FORCEPROP 1 LAST PATH I55
J 0
(-825 1650);
DISPLAY 0.978723 (-825 1650);
PAINT WHITE (-825 1650);
DISPLAY INVISIBLE (-825 1650);
FORCEPROP 1 LAST PART_NUMBER CS12492FB02
J 0
(-825 1600);
DISPLAY 0.787234 (-825 1600);
DISPLAY INVISIBLE (-825 1600);
FORCEADD Q_LED..1
R 2
(-1725 1500);
FORCEPROP 1 LAST LOCATION D8002
J 2
(-1675 1725);
DISPLAY 0.723404 (-1675 1725);
PAINT GREEN (-1675 1725);
FORCEPROP 2 LAST SEC 1
J 0
(-1625 1875);
DISPLAY 0.680851 (-1625 1875);
PAINT MONO (-1625 1875);
DISPLAY INVISIBLE (-1625 1875);
FORCEPROP 2 LASTPIN (-1575 1500) $PN A
J 0
(-1565 1510);
DISPLAY 0.680851 (-1565 1510);
PAINT MONO (-1565 1510);
FORCEPROP 2 LASTPIN (-1875 1500) $PN C
J 2
(-1885 1510);
DISPLAY 0.680851 (-1885 1510);
PAINT MONO (-1885 1510);
FORCEPROP 2 LAST COLOR LED_YELLOW
J 2
(-1675 1675);
DISPLAY 0.680851 (-1675 1675);
FORCEPROP 2 LAST MANUF_PN LTST-C190KSKT-P
J 2
(-1525 1600);
DISPLAY 0.680851 (-1525 1600);
FORCEPROP 1 LAST MATERIAL IC
J 2
(-1575 1350);
DISPLAY 0.723404 (-1575 1350);
PAINT GREEN (-1575 1350);
FORCEPROP 2 LAST PACK_TYPE SMLF
J 2
(-1525 1400);
DISPLAY 0.680851 (-1525 1400);
FORCEPROP 1 LAST NEEDS_NO_SIZE TRUE
J 2
(-1725 1500);
DISPLAY 0.468085 (-1725 1500);
PAINT GREEN (-1725 1500);
DISPLAY INVISIBLE (-1725 1500);
FORCEPROP 2 LAST CDS_LIB pure_quanta
J 2
(-1725 1500);
DISPLAY INVISIBLE (-1725 1500);
FORCEPROP 2 LAST SEC_TYPE SMLF
J 0
(-1625 1875);
DISPLAY 0.680851 (-1625 1875);
DISPLAY INVISIBLE (-1625 1875);
FORCEPROP 1 LAST PATH I56
J 2
(-1850 1580);
DISPLAY 0.723404 (-1850 1580);
PAINT GREEN (-1850 1580);
DISPLAY INVISIBLE (-1850 1580);
FORCEPROP 1 LAST PART_NUMBER BEYL0159Z00
J 2
(-1625 1635);
DISPLAY 0.723404 (-1625 1635);
PAINT GREEN (-1625 1635);
DISPLAY INVISIBLE (-1625 1635);
FORCEADD MOSFET_NCH_DUAL..1
(-3075 750);
FORCEPROP 1 LAST LOCATION Q8001
J 0
(-2924 724);
DISPLAY 0.723404 (-2924 724);
PAINT GREEN (-2924 724);
FORCEPROP 2 LAST SEC 1
J 0
(-2900 875);
DISPLAY 0.680851 (-2900 875);
PAINT MONO (-2900 875);
DISPLAY INVISIBLE (-2900 875);
FORCEPROP 2 LASTPIN (-3025 950) $PN 6
R 1
J 0
(-3035 960);
DISPLAY 0.680851 (-3035 960);
PAINT MONO (-3035 960);
FORCEPROP 2 LASTPIN (-3275 700) $PN 2
J 2
(-3285 710);
DISPLAY 0.680851 (-3285 710);
PAINT MONO (-3285 710);
FORCEPROP 2 LASTPIN (-3025 550) $PN 1
R 1
J 2
(-3035 540);
DISPLAY 0.680851 (-3035 540);
PAINT MONO (-3035 540);
FORCEPROP 1 LAST MATERIAL IC
J 0
(-2924 599);
DISPLAY 0.723404 (-2924 599);
PAINT GREEN (-2924 599);
FORCEPROP 2 LAST VALUE PJT138K
J 0
(-2900 775);
DISPLAY 0.680851 (-2900 775);
FORCEPROP 2 LAST PART_TYPE SMLF
J 0
(-2900 825);
DISPLAY 0.680851 (-2900 825);
FORCEPROP 2 LAST SEC_TYPE 
J 0
(-2900 875);
DISPLAY 0.680851 (-2900 875);
DISPLAY INVISIBLE (-2900 875);
FORCEPROP 2 LAST CDS_LIB pure_quanta
J 0
(-3075 750);
DISPLAY INVISIBLE (-3075 750);
FORCEPROP 1 LAST NEEDS_NO_SIZE TRUE
J 0
(-3075 749);
DISPLAY 0.468085 (-3075 749);
PAINT GREEN (-3075 749);
DISPLAY INVISIBLE (-3075 749);
FORCEPROP 1 LAST CDS_LMAN_SYM_OUTLINE -150,150,150,-150
J 0
(-3075 750);
DISPLAY 0.468085 (-3075 750);
PAINT GREEN (-3075 750);
DISPLAY INVISIBLE (-3075 750);
FORCEPROP 1 LAST PATH I57
J 0
(-3075 750);
DISPLAY 0.723404 (-3075 750);
PAINT GREEN (-3075 750);
DISPLAY INVISIBLE (-3075 750);
FORCEPROP 1 LAST PART_NUMBER BAM138K0003
J 0
(-2924 664);
DISPLAY 0.723404 (-2924 664);
PAINT GREEN (-2924 664);
DISPLAY INVISIBLE (-2924 664);
FORCEADD MOSFET_NCH_DUAL..2
(-2100 1175);
FORCEPROP 1 LAST LOCATION Q8001
J 0
(-1949 1151);
DISPLAY 0.723404 (-1949 1151);
PAINT GREEN (-1949 1151);
FORCEPROP 2 LAST SEC 2
J 0
(-1925 1300);
DISPLAY 0.680851 (-1925 1300);
PAINT MONO (-1925 1300);
DISPLAY INVISIBLE (-1925 1300);
FORCEPROP 2 LASTPIN (-2050 1375) $PN 3
R 1
J 0
(-2060 1385);
DISPLAY 0.680851 (-2060 1385);
PAINT MONO (-2060 1385);
FORCEPROP 2 LASTPIN (-2300 1125) $PN 5
J 2
(-2310 1135);
DISPLAY 0.680851 (-2310 1135);
PAINT MONO (-2310 1135);
FORCEPROP 2 LASTPIN (-2050 975) $PN 4
R 1
J 2
(-2060 965);
DISPLAY 0.680851 (-2060 965);
PAINT MONO (-2060 965);
FORCEPROP 1 LAST MATERIAL IC
J 0
(-1949 1026);
DISPLAY 0.723404 (-1949 1026);
PAINT GREEN (-1949 1026);
FORCEPROP 2 LAST PART_TYPE SMLF
J 0
(-1925 1250);
DISPLAY 0.680851 (-1925 1250);
FORCEPROP 2 LAST VALUE PJT138K
J 0
(-1925 1200);
DISPLAY 0.680851 (-1925 1200);
FORCEPROP 2 LAST SEC_TYPE 
J 0
(-1925 1300);
DISPLAY 0.680851 (-1925 1300);
DISPLAY INVISIBLE (-1925 1300);
FORCEPROP 1 LAST CDS_LMAN_SYM_OUTLINE -150,150,150,-150
J 0
(-2100 1175);
DISPLAY 0.468085 (-2100 1175);
PAINT GREEN (-2100 1175);
DISPLAY INVISIBLE (-2100 1175);
FORCEPROP 1 LAST NEEDS_NO_SIZE TRUE
J 0
(-1950 1066);
DISPLAY 0.468085 (-1950 1066);
PAINT GREEN (-1950 1066);
DISPLAY INVISIBLE (-1950 1066);
FORCEPROP 2 LAST CDS_LIB pure_quanta
J 0
(-2100 1175);
DISPLAY INVISIBLE (-2100 1175);
FORCEPROP 1 LAST PATH I58
J 0
(-1950 1025);
DISPLAY 0.723404 (-1950 1025);
PAINT GREEN (-1950 1025);
DISPLAY INVISIBLE (-1950 1025);
FORCEPROP 1 LAST PART_NUMBER BAM138K0003
J 0
(-1949 1081);
DISPLAY 0.723404 (-1949 1081);
PAINT GREEN (-1949 1081);
DISPLAY INVISIBLE (-1949 1081);
FORCEADD UNIVERSAL_GND..1
(-2050 675);
FORCEPROP 3 LASTPIN (-2050 725) SIG_NAME GND\g
J 0
(-2040 735);
DISPLAY 0.659574 (-2040 735);
PAINT MONO (-2040 735);
DISPLAY INVISIBLE (-2040 735);
FORCEPROP 2 LAST CDS_LIB pure_quanta_power
J 0
(-2050 675);
DISPLAY INVISIBLE (-2050 675);
FORCEPROP 1 LAST HDL_POWER GND
J 1
(-2025 600);
DISPLAY 0.872340 (-2025 600);
PAINT GREEN (-2025 600);
DISPLAY INVISIBLE (-2025 600);
FORCEPROP 1 LAST PATH I59
J 0
(-1975 675);
DISPLAY 0.872340 (-1975 675);
PAINT AQUA (-1975 675);
DISPLAY INVISIBLE (-1975 675);
FORCEADD OFFPAGE..1
(-9025 4350);
PAINT AQUA (-9025 4350);
FORCEPROP 2 LAST $XR0 80 
J 0
(-9276 4350);
DISPLAY 0.638298 (-9276 4350);
PAINT MONO (-9276 4350);
FORCEPROP 2 LAST CDS_LIB standard
J 0
(-9025 4350);
DISPLAY INVISIBLE (-9025 4350);
FORCEPROP 1 LAST OFFPAGE TRUE
J 0
(-8700 4225);
DISPLAY 0.872340 (-8700 4225);
PAINT AQUA (-8700 4225);
DISPLAY INVISIBLE (-8700 4225);
FORCEPROP 1 LAST COMMENT_BODY TRUE
J 0
(-8900 4250);
DISPLAY 0.872340 (-8900 4250);
PAINT GREEN (-8900 4250);
DISPLAY INVISIBLE (-8900 4250);
FORCEPROP 2 LAST PATH I6
J 0
(-9275 4400);
DISPLAY 0.680851 (-9275 4400);
DISPLAY INVISIBLE (-9275 4400);
FORCEADD UNIVERSAL_POWER..1
(-3025 1625);
FORCEPROP 3 LASTPIN (-3025 1575) SIG_NAME P3V3_AUX\g
J 0
(-3015 1585);
DISPLAY 0.659574 (-3015 1585);
PAINT MONO (-3015 1585);
DISPLAY INVISIBLE (-3015 1585);
FORCEPROP 1 LAST HDL_POWER P3V3_AUX
J 1
(-3025 1675);
DISPLAY 0.723404 (-3025 1675);
PAINT GREEN (-3025 1675);
FORCEPROP 2 LAST CDS_LIB pure_quanta_power
J 0
(-3025 1625);
DISPLAY INVISIBLE (-3025 1625);
FORCEPROP 1 LAST PATH I60
J 0
(-2975 1650);
DISPLAY 0.872340 (-2975 1650);
PAINT AQUA (-2975 1650);
DISPLAY INVISIBLE (-2975 1650);
FORCEADD UNIVERSAL_GND..1
(-3025 375);
FORCEPROP 3 LASTPIN (-3025 425) SIG_NAME GND\g
J 0
(-3015 435);
DISPLAY 0.659574 (-3015 435);
PAINT MONO (-3015 435);
DISPLAY INVISIBLE (-3015 435);
FORCEPROP 2 LAST CDS_LIB pure_quanta_power
J 0
(-3025 375);
DISPLAY INVISIBLE (-3025 375);
FORCEPROP 1 LAST HDL_POWER GND
J 1
(-3000 300);
DISPLAY 0.872340 (-3000 300);
PAINT GREEN (-3000 300);
DISPLAY INVISIBLE (-3000 300);
FORCEPROP 1 LAST PATH I61
J 0
(-2950 375);
DISPLAY 0.872340 (-2950 375);
PAINT AQUA (-2950 375);
DISPLAY INVISIBLE (-2950 375);
FORCEADD Q_RES..2
R 2
(-3025 1425);
FORCEPROP 1 LAST LOCATION R8028
J 2
(-3070 1550);
DISPLAY 0.978723 (-3070 1550);
FORCEPROP 0 LAST $SEC 1
J 0
(-3050 1600);
DISPLAY 0.680851 (-3050 1600);
PAINT MONO (-3050 1600);
DISPLAY INVISIBLE (-3050 1600);
FORCEPROP 0 LAST CDS_SEC 1
J 0
(-3050 1600);
DISPLAY 0.680851 (-3050 1600);
DISPLAY INVISIBLE (-3050 1600);
FORCEPROP 1 LASTPIN (-3025 1525) $PN 1
J 2
(-3030 1487);
DISPLAY 0.787234 (-3030 1487);
PAINT MONO (-3030 1487);
FORCEPROP 1 LASTPIN (-3025 1325) $PN 2
J 2
(-3030 1335);
DISPLAY 0.787234 (-3030 1335);
PAINT MONO (-3030 1335);
FORCEPROP 1 LAST VALUE 4.7K
J 2
(-3070 1500);
DISPLAY 0.978723 (-3070 1500);
FORCEPROP 1 LAST MATERIAL CHIP
J 2
(-3065 1350);
DISPLAY 0.978723 (-3065 1350);
FORCEPROP 1 LAST WATTAGE 1/16W
J 2
(-3065 1400);
DISPLAY 0.978723 (-3065 1400);
FORCEPROP 1 LAST TOLERANCE 5%
J 2
(-3070 1450);
DISPLAY 0.978723 (-3070 1450);
FORCEPROP 1 LAST PACK_TYPE 0402LF
J 2
(-3065 1250);
DISPLAY 0.978723 (-3065 1250);
FORCEPROP 2 LAST CDS_LIB pure_quanta
J 2
(-3025 1425);
DISPLAY INVISIBLE (-3025 1425);
FORCEPROP 1 LAST PATH I62
J 2
(-3075 1600);
DISPLAY 0.978723 (-3075 1600);
PAINT WHITE (-3075 1600);
DISPLAY INVISIBLE (-3075 1600);
FORCEPROP 1 LAST PART_NUMBER CS24702JB10
J 2
(-3065 1300);
DISPLAY 0.978723 (-3065 1300);
DISPLAY INVISIBLE (-3065 1300);
FORCEADD OFFPAGE..1
(-4375 700);
PAINT AQUA (-4375 700);
FORCEPROP 2 LAST $XR0 152 
J 0
(-4627 700);
DISPLAY 0.638298 (-4627 700);
PAINT MONO (-4627 700);
FORCEPROP 2 LAST CDS_LIB standard
J 0
(-4375 700);
DISPLAY INVISIBLE (-4375 700);
FORCEPROP 1 LAST OFFPAGE TRUE
J 0
(-4050 575);
DISPLAY 0.872340 (-4050 575);
PAINT AQUA (-4050 575);
DISPLAY INVISIBLE (-4050 575);
FORCEPROP 1 LAST COMMENT_BODY TRUE
J 0
(-4250 600);
DISPLAY 0.872340 (-4250 600);
PAINT GREEN (-4250 600);
DISPLAY INVISIBLE (-4250 600);
FORCEPROP 2 LAST PATH I63
J 0
(-4325 775);
DISPLAY 0.680851 (-4325 775);
DISPLAY INVISIBLE (-4325 775);
FORCEADD MOSFET_NCH_DUAL..1
(-7925 3175);
FORCEPROP 1 LAST LOCATION Q85
J 0
(-7774 3149);
DISPLAY 0.723404 (-7774 3149);
PAINT GREEN (-7774 3149);
FORCEPROP 0 LAST $SEC 1
J 0
(-7750 3300);
DISPLAY INVISIBLE (-7750 3300);
FORCEPROP 0 LAST CDS_SEC 1
J 0
(-7750 3300);
DISPLAY INVISIBLE (-7750 3300);
FORCEPROP 0 LASTPIN (-7875 3375) $PN 6
R 1
J 0
(-7885 3385);
DISPLAY 0.808511 (-7885 3385);
FORCEPROP 0 LASTPIN (-8125 3125) $PN 2
J 2
(-8135 3135);
DISPLAY 0.808511 (-8135 3135);
FORCEPROP 0 LASTPIN (-7875 2975) $PN 1
R 1
J 2
(-7885 2965);
DISPLAY 0.808511 (-7885 2965);
FORCEPROP 1 LAST MATERIAL IC
J 0
(-7774 3024);
DISPLAY 0.723404 (-7774 3024);
PAINT GREEN (-7774 3024);
FORCEPROP 2 LAST VALUE PJT138K
J 0
(-7750 3200);
DISPLAY 1.021277 (-7750 3200);
FORCEPROP 2 LAST PART_TYPE SMLF
J 0
(-7750 3250);
DISPLAY 1.021277 (-7750 3250);
FORCEPROP 1 LAST NEEDS_NO_SIZE TRUE
J 0
(-7925 3174);
DISPLAY 0.468085 (-7925 3174);
PAINT GREEN (-7925 3174);
DISPLAY INVISIBLE (-7925 3174);
FORCEPROP 1 LAST CDS_LMAN_SYM_OUTLINE -150,150,150,-150
J 0
(-7925 3175);
DISPLAY 0.468085 (-7925 3175);
PAINT GREEN (-7925 3175);
DISPLAY INVISIBLE (-7925 3175);
FORCEPROP 2 LAST CDS_LIB pure_quanta
J 0
(-7925 3175);
DISPLAY INVISIBLE (-7925 3175);
FORCEPROP 1 LAST PATH I7
J 0
(-7925 3175);
DISPLAY 0.723404 (-7925 3175);
PAINT GREEN (-7925 3175);
DISPLAY INVISIBLE (-7925 3175);
FORCEPROP 1 LAST PART_NUMBER BAM138K0003
J 0
(-7774 3089);
DISPLAY 0.723404 (-7774 3089);
PAINT GREEN (-7774 3089);
DISPLAY INVISIBLE (-7774 3089);
FORCEADD UNIVERSAL_GND..1
(-7875 2825);
FORCEPROP 3 LASTPIN (-7875 2875) SIG_NAME GND\g
J 0
(-7865 2885);
DISPLAY 0.659574 (-7865 2885);
PAINT MONO (-7865 2885);
DISPLAY INVISIBLE (-7865 2885);
FORCEPROP 2 LAST CDS_LIB pure_quanta_power
J 0
(-7875 2825);
DISPLAY INVISIBLE (-7875 2825);
FORCEPROP 1 LAST HDL_POWER GND
J 1
(-7850 2750);
DISPLAY 0.872340 (-7850 2750);
PAINT GREEN (-7850 2750);
DISPLAY INVISIBLE (-7850 2750);
FORCEPROP 1 LAST PATH I8
J 0
(-7800 2825);
DISPLAY 0.872340 (-7800 2825);
PAINT AQUA (-7800 2825);
DISPLAY INVISIBLE (-7800 2825);
FORCEADD UNIVERSAL_GND..1
(-7875 4050);
FORCEPROP 3 LASTPIN (-7875 4100) SIG_NAME GND\g
J 0
(-7865 4110);
DISPLAY 0.659574 (-7865 4110);
PAINT MONO (-7865 4110);
DISPLAY INVISIBLE (-7865 4110);
FORCEPROP 2 LAST CDS_LIB pure_quanta_power
J 0
(-7875 4050);
DISPLAY INVISIBLE (-7875 4050);
FORCEPROP 1 LAST HDL_POWER GND
J 1
(-7850 3975);
DISPLAY 0.872340 (-7850 3975);
PAINT GREEN (-7850 3975);
DISPLAY INVISIBLE (-7850 3975);
FORCEPROP 1 LAST PATH I9
J 0
(-7800 4050);
DISPLAY 0.872340 (-7800 4050);
PAINT AQUA (-7800 4050);
DISPLAY INVISIBLE (-7800 4050);
FORCEADD QUANTA_TITLE_BLOCK_C..1
(0 0);
FORCEPROP 0 LAST CDS_CON_LAST_MODIFIED Thu Sep 14 16:12:43 2023
J 0
(-1885 15);
DISPLAY INVISIBLE (-1885 15);
FORCEPROP 1 LAST CUSTOM_TXT_CDS <CON_LAST_MODIFIED>
J 0
(-1885 15);
DISPLAY 0.978723 (-1885 15);
FORCEPROP 2 LAST CUSTOM_TXT_CDS <XR_PAGE_TITLE>
J 0
(-7890 5250);
DISPLAY 0.638298 (-7890 5250);
PAINT PINK (-7890 5250);
DISPLAY INVISIBLE (-7890 5250);
FORCEPROP 1 LAST CUSTOM_TXT_CDS <NAME_2>
J 0
(-3175 50);
FORCEPROP 1 LAST CUSTOM_TXT_CDS <NAME_1>
J 0
(-3175 175);
FORCEPROP 1 LAST CUSTOM_TXT_CDS <Q_NUMBER>
J 0
(-1403 103);
DISPLAY 1.212766 (-1403 103);
FORCEPROP 1 LAST CUSTOM_TXT_CDS <Q_PROJ>
J 0
(-2382 102);
DISPLAY 1.212766 (-2382 102);
FORCEPROP 1 LAST CUSTOM_TXT_CDS <Q_REV>
J 0
(-184 103);
DISPLAY 1.212766 (-184 103);
FORCEPROP 1 LAST CUSTOM_TXT_CDS <CON_PAGE_NUM> OF <CON_TOTAL_PAGES>
J 0
(-446 18);
DISPLAY 0.978723 (-446 18);
FORCEPROP 1 LAST Q_TITLE POWER GOOD LED'S 3/3
J 0
(-9366 26);
DISPLAY 2.446809 (-9366 26);
PAINT GREEN (-9366 26);
FORCEPROP 2 LAST PAGE_BORDER TRUE
J 0
(-7890 5250);
DISPLAY 0.638298 (-7890 5250);
PAINT PINK (-7890 5250);
DISPLAY INVISIBLE (-7890 5250);
FORCEPROP 1 LAST CDS_LMAN_SYM_OUTLINE -9475,6775,100,-125
J 0
(0 0);
DISPLAY 0.468085 (0 0);
PAINT GREEN (0 0);
DISPLAY INVISIBLE (0 0);
FORCEPROP 2 LAST CDS_LIB pure_quanta
J 0
(0 0);
DISPLAY INVISIBLE (0 0);
FORCEPROP 2 LAST CDS_XR_PAGE_TITLE CR-257 : @T6G_MB_LIB.T6G(SCH_1):PAGE257
J 0
(-7890 5250);
DISPLAY 0.638298 (-7890 5250);
PAINT PINK (-7890 5250);
DISPLAY INVISIBLE (-7890 5250);
FORCEPROP 1 LAST Q_DEPT BU9
J 1
(-3763 49);
DISPLAY 1.957447 (-3763 49);
PAINT GREEN (-3763 49);
DISPLAY INVISIBLE (-3763 49);
FORCEPROP 1 LAST COMMENT_BODY TRUE
J 0
(12 -13);
DISPLAY 0.978723 (12 -13);
PAINT GREEN (12 -13);
DISPLAY INVISIBLE (12 -13);
WIRE 16 -1 (-7875 1550)(-7875 1650);
WIRE 16 -1 (-7875 5425)(-7875 5525);
WIRE 16 -1 (-4875 2125)(-4875 2225);
WIRE 16 -1 (-4875 2125)(-5375 2125);
WIRE 16 -1 (-4825 3450)(-4825 3575);
WIRE 16 -1 (-4825 3450)(-5325 3450);
WIRE 16 -1 (-4875 4675)(-4875 4750);
WIRE 16 -1 (-4875 4675)(-5375 4675);
WIRE 16 -1 (-3200 4125)(-3200 4225);
WIRE 16 -1 (-3200 5450)(-3200 5550);
WIRE 16 -1 (-4850 6000)(-4850 6100);
WIRE 16 -1 (-4850 6000)(-5400 6000);
WIRE 16 -1 (-225 4700)(-225 4800);
WIRE 16 -1 (-225 4700)(-775 4700);
WIRE 16 -1 (-250 6025)(-250 6150);
WIRE 16 -1 (-250 6025)(-750 6025);
WIRE 16 -1 (-4250 3575)(-4525 3575);
WIRE 16 -1 (-4525 3575)(-4525 3425);
WIRE 16 -1 (-4175 2425)(-4450 2425);
WIRE 16 -1 (-4450 2425)(-4450 2275);
WIRE 16 -1 (-2050 975)(-2050 725);
WIRE 16 -1 (-3025 1575)(-3025 1525);
WIRE 16 -1 (-3025 550)(-3025 425);
WIRE 16 -1 (-7875 2875)(-7875 2975);
WIRE 16 -1 (-7875 4100)(-7875 4200);
WIRE 74 -1 (-6700 5000)(-6700 5200);
WIRE 74 -1 (-8950 5000)(-6700 5000);
WIRE 74 -1 (-6700 5200)(-8950 5200);
WIRE 74 -1 (-8950 5200)(-8950 5000);
WIRE 74 -1 (-6700 6325)(-6700 6525);
WIRE 74 -1 (-8950 6325)(-6700 6325);
WIRE 74 -1 (-6700 6525)(-8950 6525);
WIRE 74 -1 (-8950 6525)(-8950 6325);
WIRE 16 -1 (-7875 3375)(-7875 3450);
WIRE 16 -1 (-7875 3450)(-7000 3450);
FORCEPROP 2 LAST SIG_NAME LED_PWRGD_PVDDCR_CPU1_P1_D
J 0
(-7860 3460);
DISPLAY 0.574468 (-7860 3460);
FORCEPROP 2 LASTPROP $XRERR UNIQUE?
J 0
(-8100 3460);
DISPLAY 0.638298 (-8100 3460);
PAINT MONO (-8100 3460);
DISPLAY INVISIBLE (-8100 3460);
WIRE 16 -1 (-7875 6000)(-7000 6000);
FORCEPROP 2 LAST SIG_NAME LED_PWRGD_PVDDCR_CPU0_P1_D
J 0
(-7860 6010);
DISPLAY 0.574468 (-7860 6010);
FORCEPROP 2 LASTPROP $XRERR UNIQUE?
J 0
(-8100 6010);
DISPLAY 0.638298 (-8100 6010);
PAINT MONO (-8100 6010);
DISPLAY INVISIBLE (-8100 6010);
WIRE 16 -1 (-7875 5925)(-7875 6000);
WIRE 16 -1 (-6700 6000)(-5600 6000);
FORCEPROP 2 LAST SIG_NAME LED_PWRGD_PVDDCR_CPU0_P1_R
J 0
(-6435 6010);
DISPLAY 0.574468 (-6435 6010);
FORCEPROP 2 LASTPROP $XRERR UNIQUE?
J 0
(-6675 6010);
DISPLAY 0.638298 (-6675 6010);
PAINT MONO (-6675 6010);
DISPLAY INVISIBLE (-6675 6010);
WIRE 16 -1 (-7875 4675)(-7000 4675);
FORCEPROP 2 LAST SIG_NAME LED_PWRGD_PVDDCR_SOC_P1_D
J 0
(-7860 4685);
DISPLAY 0.574468 (-7860 4685);
FORCEPROP 2 LASTPROP $XRERR UNIQUE?
J 0
(-8100 4685);
DISPLAY 0.638298 (-8100 4685);
PAINT MONO (-8100 4685);
DISPLAY INVISIBLE (-8100 4685);
WIRE 16 -1 (-7875 4600)(-7875 4675);
WIRE 16 -1 (-6700 4675)(-5575 4675);
FORCEPROP 2 LAST SIG_NAME LED_PWRGD_PVDDCR_SOC_P1_R
J 0
(-6485 4685);
DISPLAY 0.574468 (-6485 4685);
FORCEPROP 2 LASTPROP $XRERR UNIQUE?
J 0
(-6725 4685);
DISPLAY 0.638298 (-6725 4685);
PAINT MONO (-6725 4685);
DISPLAY INVISIBLE (-6725 4685);
WIRE 16 -1 (-6700 3450)(-5525 3450);
FORCEPROP 2 LAST SIG_NAME LED_PWRGD_PVDDCR_CPU1_P1_R
J 0
(-6435 3460);
DISPLAY 0.574468 (-6435 3460);
FORCEPROP 2 LASTPROP $XRERR UNIQUE?
J 0
(-6675 3460);
DISPLAY 0.638298 (-6675 3460);
PAINT MONO (-6675 3460);
DISPLAY INVISIBLE (-6675 3460);
WIRE 16 -1 (-6700 2125)(-5575 2125);
FORCEPROP 2 LAST SIG_NAME LED_PWRGD_PVDDIO_P1_R
J 0
(-6535 2135);
DISPLAY 0.723404 (-6535 2135);
FORCEPROP 2 LASTPROP $XRERR UNIQUE?
J 0
(-6775 2135);
DISPLAY 0.638298 (-6775 2135);
PAINT MONO (-6775 2135);
DISPLAY INVISIBLE (-6775 2135);
WIRE 16 -1 (-8125 5675)(-8975 5675);
FORCEPROP 2 LAST SIG_NAME FM_LED_PWRGD_PVDDCR_CPU0_P1
J 0
(-8960 5685);
DISPLAY 0.574468 (-8960 5685);
WIRE 16 -1 (-8125 4350)(-8975 4350);
FORCEPROP 2 LAST SIG_NAME FM_LED_PWRGD_PVDDCR_SOC_P1
J 0
(-8910 4360);
DISPLAY 0.574468 (-8910 4360);
WIRE 16 -1 (-8125 3125)(-8975 3125);
FORCEPROP 2 LAST SIG_NAME FM_LED_PWRGD_PVDDCR_CPU1_P1
J 0
(-8935 3135);
DISPLAY 0.574468 (-8935 3135);
WIRE 16 -1 (-8125 1800)(-8975 1800);
FORCEPROP 2 LAST SIG_NAME FM_LED_PWRGD_PVDDIO_P1
J 0
(-8985 1810);
DISPLAY 0.723404 (-8985 1810);
WIRE 16 -1 (-3200 5950)(-3200 6025);
FORCEPROP 2 LAST SIG_NAME LED_PWRGD_PVDD11_S3_P1_D
J 0
(-3260 6035);
DISPLAY 0.723404 (-3260 6035);
FORCEPROP 2 LASTPROP $XRERR UNIQUE?
J 0
(-3500 6035);
DISPLAY 0.638298 (-3500 6035);
PAINT MONO (-3500 6035);
DISPLAY INVISIBLE (-3500 6035);
WIRE 16 -1 (-3200 6025)(-2325 6025);
WIRE 16 -1 (-2025 6025)(-950 6025);
FORCEPROP 2 LAST SIG_NAME LED_PWRGD_PVDD11_S3_P1_R
J 0
(-1860 6035);
DISPLAY 0.723404 (-1860 6035);
FORCEPROP 2 LASTPROP $XRERR UNIQUE?
J 0
(-2100 6035);
DISPLAY 0.638298 (-2100 6035);
PAINT MONO (-2100 6035);
DISPLAY INVISIBLE (-2100 6035);
WIRE 16 -1 (-3450 5700)(-4300 5700);
FORCEPROP 2 LAST SIG_NAME FM_LED_PWRGD_PVDD11_S3_P1
J 0
(-4235 5710);
DISPLAY 0.574468 (-4235 5710);
WIRE 74 -1 (-1950 6350)(-1950 6550);
WIRE 74 -1 (-4275 6350)(-1950 6350);
WIRE 74 -1 (-1950 6550)(-4275 6550);
WIRE 74 -1 (-4275 6550)(-4275 6350);
WIRE 16 -1 (-3200 4625)(-3200 4700);
FORCEPROP 2 LAST SIG_NAME LED_PWRGD_PVDD18_S5_P1_D
J 0
(-3285 4725);
DISPLAY 0.723404 (-3285 4725);
FORCEPROP 2 LASTPROP $XRERR UNIQUE?
J 0
(-3525 4725);
DISPLAY 0.638298 (-3525 4725);
PAINT MONO (-3525 4725);
DISPLAY INVISIBLE (-3525 4725);
WIRE 16 -1 (-3200 4700)(-2325 4700);
WIRE 16 -1 (-2025 4700)(-975 4700);
FORCEPROP 2 LAST SIG_NAME LED_PWRGD_PVDD18_S5_P1_R
J 0
(-1885 4710);
DISPLAY 0.723404 (-1885 4710);
FORCEPROP 2 LASTPROP $XRERR UNIQUE?
J 0
(-2125 4710);
DISPLAY 0.638298 (-2125 4710);
PAINT MONO (-2125 4710);
DISPLAY INVISIBLE (-2125 4710);
WIRE 16 -1 (-2900 3575)(-2175 3575);
FORCEPROP 2 LAST SIG_NAME LED_P12V_AUX_R2
J 0
(-2810 3585);
DISPLAY 0.680851 (-2810 3585);
FORCEPROP 2 LASTPROP $XRERR UNIQUE?
J 0
(-3050 3585);
DISPLAY 0.638298 (-3050 3585);
PAINT MONO (-3050 3585);
DISPLAY INVISIBLE (-3050 3585);
WIRE 16 -1 (-1975 3575)(-1175 3575);
FORCEPROP 2 LAST SIG_NAME LED_P12V_AUX_R3
J 0
(-1835 3585);
DISPLAY 0.680851 (-1835 3585);
FORCEPROP 2 LASTPROP $XRERR UNIQUE?
J 0
(-2075 3585);
DISPLAY 0.638298 (-2075 3585);
PAINT MONO (-2075 3585);
DISPLAY INVISIBLE (-2075 3585);
WIRE 16 -1 (-3950 3575)(-3100 3575);
FORCEPROP 2 LAST SIG_NAME LED_P12V_AUX_R1
J 0
(-3785 3585);
DISPLAY 0.680851 (-3785 3585);
FORCEPROP 2 LASTPROP $XRERR UNIQUE?
J 0
(-4025 3585);
DISPLAY 0.638298 (-4025 3585);
PAINT MONO (-4025 3585);
DISPLAY INVISIBLE (-4025 3585);
WIRE 74 -1 (-1950 3750)(-1950 3950);
WIRE 74 -1 (-4275 3750)(-1950 3750);
WIRE 74 -1 (-1950 3950)(-4275 3950);
WIRE 74 -1 (-4275 3950)(-4275 3750);
WIRE 16 -1 (-3450 4375)(-4300 4375);
FORCEPROP 2 LAST SIG_NAME FM_LED_PWRGD_PVDD18_S5_P1
J 0
(-4235 4385);
DISPLAY 0.574468 (-4235 4385);
WIRE 74 -1 (-1950 5025)(-1950 5225);
WIRE 74 -1 (-4275 5025)(-1950 5025);
WIRE 74 -1 (-1950 5225)(-4275 5225);
WIRE 74 -1 (-4275 5225)(-4275 5025);
WIRE 74 -1 (-6675 3775)(-6675 3975);
WIRE 74 -1 (-8950 3775)(-6675 3775);
WIRE 74 -1 (-6675 3975)(-8950 3975);
WIRE 74 -1 (-8950 3975)(-8950 3775);
WIRE 16 -1 (-7875 2050)(-7875 2125);
FORCEPROP 2 LAST SIG_NAME LED_PWRGD_PVDDIO_P1_D
J 0
(-7860 2135);
DISPLAY 0.723404 (-7860 2135);
FORCEPROP 2 LASTPROP $XRERR UNIQUE?
J 0
(-8100 2135);
DISPLAY 0.638298 (-8100 2135);
PAINT MONO (-8100 2135);
DISPLAY INVISIBLE (-8100 2135);
WIRE 16 -1 (-7875 2125)(-7000 2125);
WIRE 74 -1 (-6675 2450)(-6675 2650);
WIRE 74 -1 (-8950 2450)(-6675 2450);
WIRE 74 -1 (-6675 2650)(-8950 2650);
WIRE 74 -1 (-8950 2650)(-8950 2450);
WIRE 16 -1 (-2050 1500)(-1875 1500);
WIRE 16 -1 (-2050 1375)(-2050 1500);
FORCEPROP 2 LAST SIG_NAME LED_P12V_SCM_FAULT_D2
J 0
(-2535 1535);
DISPLAY 0.553191 (-2535 1535);
FORCEPROP 2 LASTPROP $XRERR UNIQUE?
J 0
(-2775 1535);
DISPLAY 0.638298 (-2775 1535);
PAINT MONO (-2775 1535);
DISPLAY INVISIBLE (-2775 1535);
WIRE 16 -1 (-875 1500)(-1575 1500);
FORCEPROP 2 LAST SIG_NAME LED_P12V_SCM_FAULT
J 0
(-1485 1510);
DISPLAY 0.680851 (-1485 1510);
FORCEPROP 2 LASTPROP $XRERR UNIQUE?
J 0
(-1725 1510);
DISPLAY 0.638298 (-1725 1510);
PAINT MONO (-1725 1510);
DISPLAY INVISIBLE (-1725 1510);
WIRE 74 -1 (-1875 1750)(-1875 1950);
WIRE 74 -1 (-4200 1750)(-1875 1750);
WIRE 74 -1 (-1875 1950)(-4200 1950);
WIRE 74 -1 (-4200 1950)(-4200 1750);
WIRE 16 -1 (-775 3775)(-775 3575);
WIRE 16 -1 (-775 3575)(-975 3575);
WIRE 16 -1 (-325 1700)(-325 1500);
WIRE 16 -1 (-325 1500)(-675 1500);
WIRE 16 -1 (-3275 700)(-4325 700);
FORCEPROP 2 LAST SIG_NAME P12V_SCM_FAULT_R_N
J 0
(-4060 710);
DISPLAY 0.680851 (-4060 710);
WIRE 16 -1 (-2300 1125)(-3025 1125);
FORCEPROP 2 LAST SIG_NAME LED_P12V_SCM_FAULT_D1
J 0
(-2960 1135);
DISPLAY 0.553191 (-2960 1135);
FORCEPROP 2 LASTPROP $XRERR UNIQUE?
J 0
(-3200 1135);
DISPLAY 0.638298 (-3200 1135);
PAINT MONO (-3200 1135);
DISPLAY INVISIBLE (-3200 1135);
WIRE 16 -1 (-3025 1325)(-3025 1125);
WIRE 16 -1 (-3025 1125)(-3025 950);
WIRE 16 -1 (-1900 2425)(-1100 2425);
FORCEPROP 2 LAST SIG_NAME LED_P12V_PSU_R3
J 0
(-1760 2435);
DISPLAY 0.680851 (-1760 2435);
FORCEPROP 2 LASTPROP $XRERR UNIQUE?
J 0
(-2000 2435);
DISPLAY 0.638298 (-2000 2435);
PAINT MONO (-2000 2435);
DISPLAY INVISIBLE (-2000 2435);
WIRE 16 -1 (-2825 2425)(-2100 2425);
FORCEPROP 2 LAST SIG_NAME LED_P12V_PSU_R2
J 0
(-2735 2435);
DISPLAY 0.680851 (-2735 2435);
FORCEPROP 2 LASTPROP $XRERR UNIQUE?
J 0
(-2975 2435);
DISPLAY 0.638298 (-2975 2435);
PAINT MONO (-2975 2435);
DISPLAY INVISIBLE (-2975 2435);
WIRE 16 -1 (-700 2625)(-700 2425);
WIRE 16 -1 (-700 2425)(-900 2425);
WIRE 74 -1 (-1875 2800)(-1875 3000);
WIRE 74 -1 (-4200 2800)(-1875 2800);
WIRE 74 -1 (-1875 3000)(-4200 3000);
WIRE 74 -1 (-4200 3000)(-4200 2800);
WIRE 16 -1 (-3875 2425)(-3025 2425);
FORCEPROP 2 LAST SIG_NAME LED_P12V_PSU_R1
J 0
(-3710 2435);
DISPLAY 0.680851 (-3710 2435);
FORCEPROP 2 LASTPROP $XRERR UNIQUE?
J 0
(-3950 2435);
DISPLAY 0.638298 (-3950 2435);
PAINT MONO (-3950 2435);
DISPLAY INVISIBLE (-3950 2435);
DOT 1 (-3025 1125);
FORCENOTE
P12V_SCM FAULT                0 = ON
(-4075 1825) 0;
DISPLAY LEFT (-4075 1825);
DISPLAY 1.276596 (-4075 1825);
PAINT WHITE (-4075 1825);
FORCENOTE
P12V_PSU                     1 = ON
(-4075 2875) 0;
DISPLAY LEFT (-4075 2875);
DISPLAY 1.276596 (-4075 2875);
PAINT WHITE (-4075 2875);
FORCENOTE
PWRGD_PVDDCR_SOC_P1         1 = ON
(-8825 5075) 0;
DISPLAY LEFT (-8825 5075);
DISPLAY 1.276596 (-8825 5075);
PAINT WHITE (-8825 5075);
FORCENOTE
PWRGD_PVDDCR_CPU1_P1        1 = ON
(-8825 3850) 0;
DISPLAY LEFT (-8825 3850);
DISPLAY 1.276596 (-8825 3850);
PAINT WHITE (-8825 3850);
FORCENOTE
PWRGD_PVDDCR_CPU0_P1        1 = ON
(-8825 6400) 0;
DISPLAY LEFT (-8825 6400);
DISPLAY 1.276596 (-8825 6400);
PAINT WHITE (-8825 6400);
FORCENOTE
PWRGD_PVDD11_S3_P1           1 = ON
(-4150 6425) 0;
DISPLAY LEFT (-4150 6425);
DISPLAY 1.276596 (-4150 6425);
PAINT WHITE (-4150 6425);
FORCENOTE
P12V_AUX                     1 = ON
(-4150 3825) 0;
DISPLAY LEFT (-4150 3825);
DISPLAY 1.276596 (-4150 3825);
PAINT WHITE (-4150 3825);
FORCENOTE
PWRGD_PVDD18_S5_P1          1 = ON
(-4150 5100) 0;
DISPLAY LEFT (-4150 5100);
DISPLAY 1.276596 (-4150 5100);
PAINT WHITE (-4150 5100);
FORCENOTE
PWRGD_PVDDIO_P1             1 = ON
(-8825 2525) 0;
DISPLAY LEFT (-8825 2525);
DISPLAY 1.276596 (-8825 2525);
PAINT WHITE (-8825 2525);
QUIT
